G04 ================== begin FILE IDENTIFICATION RECORD ==================*
G04 Layout Name:  D:/<user>/Wistron_project/16318-2/gbr/16318-2.brd*
G04 Film Name:    BMASK*
G04 File Format:  Gerber RS274X*
G04 File Origin:  Cadence Allegro 16.5-S056*
G04 Origin Date:  Mon Aug 07 11:09:11 2017*
G04 *
G04 Layer:  VIA CLASS/SOLDERMASK_BOTTOM*
G04 Layer:  PIN/SOLDERMASK_BOTTOM*
G04 Layer:  PACKAGE GEOMETRY/SOLDERMASK_BOTTOM*
G04 Layer:  DRAWING FORMAT/LAYER_PCB_STORY*
G04 Layer:  DRAWING FORMAT/LAYER_SOLDER_B*
G04 Layer:  BOARD GEOMETRY/SOLDERMASK_BOTTOM*
G04 *
G04 Offset:    (0.00 0.00)*
G04 Mirror:    No*
G04 Mode:      Positive*
G04 Rotation:  0*
G04 FullContactRelief:  No*
G04 UndefLineWidth:     6.00*
G04 ================== end FILE IDENTIFICATION RECORD ====================*
%FSLAX35Y35*MOIN*%
%IR0*IPPOS*OFA0.00000B0.00000*MIA0B0*SFA1.00000B1.00000*%
%AMMACRO32*
4,1,40,.011,.007,
.011,-.007,
.010939,-.007695,
.010759,-.008368,
.010464,-.009,
.010064,-.009571,
.009571,-.010064,
.009,-.010464,
.008368,-.010759,
.007695,-.010939,
.007,-.011,
-.007,-.011,
-.007695,-.010939,
-.008368,-.010759,
-.009,-.010464,
-.009571,-.010064,
-.010064,-.009571,
-.010464,-.009,
-.010759,-.008368,
-.010939,-.007695,
-.011,-.007,
-.011,.007,
-.010939,.007695,
-.010759,.008368,
-.010464,.009,
-.010064,.009571,
-.009571,.010064,
-.009,.010464,
-.008368,.010759,
-.007695,.010939,
-.007,.011,
.007,.011,
.007695,.010939,
.008368,.010759,
.009,.010464,
.009571,.010064,
.010064,.009571,
.010464,.009,
.010759,.008368,
.010939,.007695,
.011,.007,
0.0*
%
%ADD32MACRO32*%
%AMMACRO26*
4,1,40,.013,-.017,
-.013,-.017,
-.013695,-.016939,
-.014368,-.016759,
-.015,-.016464,
-.015571,-.016064,
-.016064,-.015571,
-.016464,-.015,
-.016759,-.014368,
-.016939,-.013695,
-.017,-.013,
-.017,.013,
-.016939,.013695,
-.016759,.014368,
-.016464,.015,
-.016064,.015571,
-.015571,.016064,
-.015,.016464,
-.014368,.016759,
-.013695,.016939,
-.013,.017,
.013,.017,
.013695,.016939,
.014368,.016759,
.015,.016464,
.015571,.016064,
.016064,.015571,
.016464,.015,
.016759,.014368,
.016939,.013695,
.017,.013,
.017,-.013,
.016939,-.013695,
.016759,-.014368,
.016464,-.015,
.016064,-.015571,
.015571,-.016064,
.015,-.016464,
.014368,-.016759,
.013695,-.016939,
.013,-.017,
0.0*
%
%ADD26MACRO26*%
%AMMACRO24*
4,1,40,-.017,-.013,
-.017,.013,
-.016939,.013695,
-.016759,.014368,
-.016464,.015,
-.016064,.015571,
-.015571,.016064,
-.015,.016464,
-.014368,.016759,
-.013695,.016939,
-.013,.017,
.013,.017,
.013695,.016939,
.014368,.016759,
.015,.016464,
.015571,.016064,
.016064,.015571,
.016464,.015,
.016759,.014368,
.016939,.013695,
.017,.013,
.017,-.013,
.016939,-.013695,
.016759,-.014368,
.016464,-.015,
.016064,-.015571,
.015571,-.016064,
.015,-.016464,
.014368,-.016759,
.013695,-.016939,
.013,-.017,
-.013,-.017,
-.013695,-.016939,
-.014368,-.016759,
-.015,-.016464,
-.015571,-.016064,
-.016064,-.015571,
-.016464,-.015,
-.016759,-.014368,
-.016939,-.013695,
-.017,-.013,
0.0*
%
%ADD24MACRO24*%
%ADD50O,.06X.111*%
%ADD10C,.02*%
%ADD63C,.03*%
%ADD69C,.022*%
%ADD66C,.05*%
%ADD55C,.014*%
%ADD47C,.032*%
%AMMACRO80*
4,1,40,-.007,-.004,
-.007,.004,
-.00697,.004347,
-.006879,.004684,
-.006732,.005,
-.006532,.005286,
-.006286,.005532,
-.006,.005732,
-.005684,.005879,
-.005347,.00597,
-.005,.006,
.005,.006,
.005347,.00597,
.005684,.005879,
.006,.005732,
.006286,.005532,
.006532,.005286,
.006732,.005,
.006879,.004684,
.00697,.004347,
.007,.004,
.007,-.004,
.00697,-.004347,
.006879,-.004684,
.006732,-.005,
.006532,-.005286,
.006286,-.005532,
.006,-.005732,
.005684,-.005879,
.005347,-.00597,
.005,-.006,
-.005,-.006,
-.005347,-.00597,
-.005684,-.005879,
-.006,-.005732,
-.006286,-.005532,
-.006532,-.005286,
-.006732,-.005,
-.006879,-.004684,
-.00697,-.004347,
-.007,-.004,
0.0*
%
%ADD80MACRO80*%
%ADD56C,.042*%
%ADD27C,.024*%
%AMMACRO74*
4,1,40,-.004,.007,
.004,.007,
.004347,.00697,
.004684,.006879,
.005,.006732,
.005286,.006532,
.005532,.006286,
.005732,.006,
.005879,.005684,
.00597,.005347,
.006,.005,
.006,-.005,
.00597,-.005347,
.005879,-.005684,
.005732,-.006,
.005532,-.006286,
.005286,-.006532,
.005,-.006732,
.004684,-.006879,
.004347,-.00697,
.004,-.007,
-.004,-.007,
-.004347,-.00697,
-.004684,-.006879,
-.005,-.006732,
-.005286,-.006532,
-.005532,-.006286,
-.005732,-.006,
-.005879,-.005684,
-.00597,-.005347,
-.006,-.005,
-.006,.005,
-.00597,.005347,
-.005879,.005684,
-.005732,.006,
-.005532,.006286,
-.005286,.006532,
-.005,.006732,
-.004684,.006879,
-.004347,.00697,
-.004,.007,
0.0*
%
%ADD74MACRO74*%
%ADD54C,.034*%
%ADD44C,.08*%
%ADD72C,.036*%
%ADD45C,.028*%
%ADD71C,.029*%
%ADD11C,.056*%
%ADD52C,.048*%
%ADD65C,.094*%
%ADD12C,.086*%
%ADD64C,.097*%
%AMMACRO62*
4,1,40,.0225,.007,
.022378,.008389,
.022018,.009736,
.021428,.011,
.020628,.012142,
.019642,.013128,
.0185,.013928,
.017236,.014518,
.015889,.014878,
.0145,.015,
-.0145,.015,
-.015889,.014878,
-.017236,.014518,
-.0185,.013928,
-.019642,.013128,
-.020628,.012142,
-.021428,.011,
-.022018,.009736,
-.022378,.008389,
-.0225,.007,
-.0225,-.007,
-.022378,-.008389,
-.022018,-.009736,
-.021428,-.011,
-.020628,-.012142,
-.019642,-.013128,
-.0185,-.013928,
-.017236,-.014518,
-.015889,-.014878,
-.0145,-.015,
.0145,-.015,
.015889,-.014878,
.017236,-.014518,
.0185,-.013928,
.019642,-.013128,
.020628,-.012142,
.021428,-.011,
.022018,-.009736,
.022378,-.008389,
.0225,-.007,
.0225,.007,
0.0*
%
%ADD62MACRO62*%
%AMMACRO61*
4,1,40,.008,.014,
-.008,.014,
-.008695,.013939,
-.009368,.013759,
-.01,.013464,
-.010571,.013064,
-.011064,.012571,
-.011464,.012,
-.011759,.011368,
-.011939,.010695,
-.012,.01,
-.012,-.01,
-.011939,-.010695,
-.011759,-.011368,
-.011464,-.012,
-.011064,-.012571,
-.010571,-.013064,
-.01,-.013464,
-.009368,-.013759,
-.008695,-.013939,
-.008,-.014,
.008,-.014,
.008695,-.013939,
.009368,-.013759,
.01,-.013464,
.010571,-.013064,
.011064,-.012571,
.011464,-.012,
.011759,-.011368,
.011939,-.010695,
.012,-.01,
.012,.01,
.011939,.010695,
.011759,.011368,
.011464,.012,
.011064,.012571,
.010571,.013064,
.01,.013464,
.009368,.013759,
.008695,.013939,
.008,.014,
0.0*
%
%ADD61MACRO61*%
%AMMACRO60*
4,1,40,.014,-.008,
.014,.008,
.013939,.008695,
.013759,.009368,
.013464,.01,
.013064,.010571,
.012571,.011064,
.012,.011464,
.011368,.011759,
.010695,.011939,
.01,.012,
-.01,.012,
-.010695,.011939,
-.011368,.011759,
-.012,.011464,
-.012571,.011064,
-.013064,.010571,
-.013464,.01,
-.013759,.009368,
-.013939,.008695,
-.014,.008,
-.014,-.008,
-.013939,-.008695,
-.013759,-.009368,
-.013464,-.01,
-.013064,-.010571,
-.012571,-.011064,
-.012,-.011464,
-.011368,-.011759,
-.010695,-.011939,
-.01,-.012,
.01,-.012,
.010695,-.011939,
.011368,-.011759,
.012,-.011464,
.012571,-.011064,
.013064,-.010571,
.013464,-.01,
.013759,-.009368,
.013939,-.008695,
.014,-.008,
0.0*
%
%ADD60MACRO60*%
%AMMACRO22*
4,1,40,.007,-.011,
-.007,-.011,
-.007695,-.010939,
-.008368,-.010759,
-.009,-.010464,
-.009571,-.010064,
-.010064,-.009571,
-.010464,-.009,
-.010759,-.008368,
-.010939,-.007695,
-.011,-.007,
-.011,.007,
-.010939,.007695,
-.010759,.008368,
-.010464,.009,
-.010064,.009571,
-.009571,.010064,
-.009,.010464,
-.008368,.010759,
-.007695,.010939,
-.007,.011,
.007,.011,
.007695,.010939,
.008368,.010759,
.009,.010464,
.009571,.010064,
.010064,.009571,
.010464,.009,
.010759,.008368,
.010939,.007695,
.011,.007,
.011,-.007,
.010939,-.007695,
.010759,-.008368,
.010464,-.009,
.010064,-.009571,
.009571,-.010064,
.009,-.010464,
.008368,-.010759,
.007695,-.010939,
.007,-.011,
0.0*
%
%ADD22MACRO22*%
%AMMACRO15*
4,1,40,-.011,-.007,
-.011,.007,
-.010939,.007695,
-.010759,.008368,
-.010464,.009,
-.010064,.009571,
-.009571,.010064,
-.009,.010464,
-.008368,.010759,
-.007695,.010939,
-.007,.011,
.007,.011,
.007695,.010939,
.008368,.010759,
.009,.010464,
.009571,.010064,
.010064,.009571,
.010464,.009,
.010759,.008368,
.010939,.007695,
.011,.007,
.011,-.007,
.010939,-.007695,
.010759,-.008368,
.010464,-.009,
.010064,-.009571,
.009571,-.010064,
.009,-.010464,
.008368,-.010759,
.007695,-.010939,
.007,-.011,
-.007,-.011,
-.007695,-.010939,
-.008368,-.010759,
-.009,-.010464,
-.009571,-.010064,
-.010064,-.009571,
-.010464,-.009,
-.010759,-.008368,
-.010939,-.007695,
-.011,-.007,
0.0*
%
%ADD15MACRO15*%
%AMMACRO36*
4,1,40,-.012,-.008,
-.012,.008,
-.011939,.008695,
-.011759,.009368,
-.011464,.01,
-.011064,.010571,
-.010571,.011064,
-.01,.011464,
-.009368,.011759,
-.008695,.011939,
-.008,.012,
.008,.012,
.008695,.011939,
.009368,.011759,
.01,.011464,
.010571,.011064,
.011064,.010571,
.011464,.01,
.011759,.009368,
.011939,.008695,
.012,.008,
.012,-.008,
.011939,-.008695,
.011759,-.009368,
.011464,-.01,
.011064,-.010571,
.010571,-.011064,
.01,-.011464,
.009368,-.011759,
.008695,-.011939,
.008,-.012,
-.008,-.012,
-.008695,-.011939,
-.009368,-.011759,
-.01,-.011464,
-.010571,-.011064,
-.011064,-.010571,
-.011464,-.01,
-.011759,-.009368,
-.011939,-.008695,
-.012,-.008,
0.0*
%
%ADD36MACRO36*%
%AMMACRO38*
4,1,40,-.008,.012,
.008,.012,
.008695,.011939,
.009368,.011759,
.01,.011464,
.010571,.011064,
.011064,.010571,
.011464,.01,
.011759,.009368,
.011939,.008695,
.012,.008,
.012,-.008,
.011939,-.008695,
.011759,-.009368,
.011464,-.01,
.011064,-.010571,
.010571,-.011064,
.01,-.011464,
.009368,-.011759,
.008695,-.011939,
.008,-.012,
-.008,-.012,
-.008695,-.011939,
-.009368,-.011759,
-.01,-.011464,
-.010571,-.011064,
-.011064,-.010571,
-.011464,-.01,
-.011759,-.009368,
-.011939,-.008695,
-.012,-.008,
-.012,.008,
-.011939,.008695,
-.011759,.009368,
-.011464,.01,
-.011064,.010571,
-.010571,.011064,
-.01,.011464,
-.009368,.011759,
-.008695,.011939,
-.008,.012,
0.0*
%
%ADD38MACRO38*%
%AMMACRO40*
4,1,40,-.013,.017,
.013,.017,
.013695,.016939,
.014368,.016759,
.015,.016464,
.015571,.016064,
.016064,.015571,
.016464,.015,
.016759,.014368,
.016939,.013695,
.017,.013,
.017,-.013,
.016939,-.013695,
.016759,-.014368,
.016464,-.015,
.016064,-.015571,
.015571,-.016064,
.015,-.016464,
.014368,-.016759,
.013695,-.016939,
.013,-.017,
-.013,-.017,
-.013695,-.016939,
-.014368,-.016759,
-.015,-.016464,
-.015571,-.016064,
-.016064,-.015571,
-.016464,-.015,
-.016759,-.014368,
-.016939,-.013695,
-.017,-.013,
-.017,.013,
-.016939,.013695,
-.016759,.014368,
-.016464,.015,
-.016064,.015571,
-.015571,.016064,
-.015,.016464,
-.014368,.016759,
-.013695,.016939,
-.013,.017,
0.0*
%
%ADD40MACRO40*%
%AMMACRO42*
4,1,40,.017,.013,
.017,-.013,
.016939,-.013695,
.016759,-.014368,
.016464,-.015,
.016064,-.015571,
.015571,-.016064,
.015,-.016464,
.014368,-.016759,
.013695,-.016939,
.013,-.017,
-.013,-.017,
-.013695,-.016939,
-.014368,-.016759,
-.015,-.016464,
-.015571,-.016064,
-.016064,-.015571,
-.016464,-.015,
-.016759,-.014368,
-.016939,-.013695,
-.017,-.013,
-.017,.013,
-.016939,.013695,
-.016759,.014368,
-.016464,.015,
-.016064,.015571,
-.015571,.016064,
-.015,.016464,
-.014368,.016759,
-.013695,.016939,
-.013,.017,
.013,.017,
.013695,.016939,
.014368,.016759,
.015,.016464,
.015571,.016064,
.016064,.015571,
.016464,.015,
.016759,.014368,
.016939,.013695,
.017,.013,
0.0*
%
%ADD42MACRO42*%
%AMMACRO81*
4,1,6,-.0135,-.005,
-.0065,-.005,
.0135,-.025,
.0135,.025,
-.0065,.005,
-.0135,.005,
-.0135,-.005,
0.0*
%
%ADD81MACRO81*%
%AMMACRO33*
4,1,40,.007,-.011,
-.007,-.011,
-.007695,-.010939,
-.008368,-.010759,
-.009,-.010464,
-.009571,-.010064,
-.010064,-.009571,
-.010464,-.009,
-.010759,-.008368,
-.010939,-.007695,
-.011,-.007,
-.011,.007,
-.010939,.007695,
-.010759,.008368,
-.010464,.009,
-.010064,.009571,
-.009571,.010064,
-.009,.010464,
-.008368,.010759,
-.007695,.010939,
-.007,.011,
.007,.011,
.007695,.010939,
.008368,.010759,
.009,.010464,
.009571,.010064,
.010064,.009571,
.010464,.009,
.010759,.008368,
.010939,.007695,
.011,.007,
.011,-.007,
.010939,-.007695,
.010759,-.008368,
.010464,-.009,
.010064,-.009571,
.009571,-.010064,
.009,-.010464,
.008368,-.010759,
.007695,-.010939,
.007,-.011,
0.0*
%
%ADD33MACRO33*%
%AMMACRO16*
4,1,40,-.011,-.007,
-.011,.007,
-.010939,.007695,
-.010759,.008368,
-.010464,.009,
-.010064,.009571,
-.009571,.010064,
-.009,.010464,
-.008368,.010759,
-.007695,.010939,
-.007,.011,
.007,.011,
.007695,.010939,
.008368,.010759,
.009,.010464,
.009571,.010064,
.010064,.009571,
.010464,.009,
.010759,.008368,
.010939,.007695,
.011,.007,
.011,-.007,
.010939,-.007695,
.010759,-.008368,
.010464,-.009,
.010064,-.009571,
.009571,-.010064,
.009,-.010464,
.008368,-.010759,
.007695,-.010939,
.007,-.011,
-.007,-.011,
-.007695,-.010939,
-.008368,-.010759,
-.009,-.010464,
-.009571,-.010064,
-.010064,-.009571,
-.010464,-.009,
-.010759,-.008368,
-.010939,-.007695,
-.011,-.007,
0.0*
%
%ADD16MACRO16*%
%AMMACRO35*
4,1,40,-.012,-.008,
-.012,.008,
-.011939,.008695,
-.011759,.009368,
-.011464,.01,
-.011064,.010571,
-.010571,.011064,
-.01,.011464,
-.009368,.011759,
-.008695,.011939,
-.008,.012,
.008,.012,
.008695,.011939,
.009368,.011759,
.01,.011464,
.010571,.011064,
.011064,.010571,
.011464,.01,
.011759,.009368,
.011939,.008695,
.012,.008,
.012,-.008,
.011939,-.008695,
.011759,-.009368,
.011464,-.01,
.011064,-.010571,
.010571,-.011064,
.01,-.011464,
.009368,-.011759,
.008695,-.011939,
.008,-.012,
-.008,-.012,
-.008695,-.011939,
-.009368,-.011759,
-.01,-.011464,
-.010571,-.011064,
-.011064,-.010571,
-.011464,-.01,
-.011759,-.009368,
-.011939,-.008695,
-.012,-.008,
0.0*
%
%ADD35MACRO35*%
%AMMACRO37*
4,1,40,-.008,.012,
.008,.012,
.008695,.011939,
.009368,.011759,
.01,.011464,
.010571,.011064,
.011064,.010571,
.011464,.01,
.011759,.009368,
.011939,.008695,
.012,.008,
.012,-.008,
.011939,-.008695,
.011759,-.009368,
.011464,-.01,
.011064,-.010571,
.010571,-.011064,
.01,-.011464,
.009368,-.011759,
.008695,-.011939,
.008,-.012,
-.008,-.012,
-.008695,-.011939,
-.009368,-.011759,
-.01,-.011464,
-.010571,-.011064,
-.011064,-.010571,
-.011464,-.01,
-.011759,-.009368,
-.011939,-.008695,
-.012,-.008,
-.012,.008,
-.011939,.008695,
-.011759,.009368,
-.011464,.01,
-.011064,.010571,
-.010571,.011064,
-.01,.011464,
-.009368,.011759,
-.008695,.011939,
-.008,.012,
0.0*
%
%ADD37MACRO37*%
%AMMACRO41*
4,1,40,-.013,.017,
.013,.017,
.013695,.016939,
.014368,.016759,
.015,.016464,
.015571,.016064,
.016064,.015571,
.016464,.015,
.016759,.014368,
.016939,.013695,
.017,.013,
.017,-.013,
.016939,-.013695,
.016759,-.014368,
.016464,-.015,
.016064,-.015571,
.015571,-.016064,
.015,-.016464,
.014368,-.016759,
.013695,-.016939,
.013,-.017,
-.013,-.017,
-.013695,-.016939,
-.014368,-.016759,
-.015,-.016464,
-.015571,-.016064,
-.016064,-.015571,
-.016464,-.015,
-.016759,-.014368,
-.016939,-.013695,
-.017,-.013,
-.017,.013,
-.016939,.013695,
-.016759,.014368,
-.016464,.015,
-.016064,.015571,
-.015571,.016064,
-.015,.016464,
-.014368,.016759,
-.013695,.016939,
-.013,.017,
0.0*
%
%ADD41MACRO41*%
%AMMACRO43*
4,1,40,.017,.013,
.017,-.013,
.016939,-.013695,
.016759,-.014368,
.016464,-.015,
.016064,-.015571,
.015571,-.016064,
.015,-.016464,
.014368,-.016759,
.013695,-.016939,
.013,-.017,
-.013,-.017,
-.013695,-.016939,
-.014368,-.016759,
-.015,-.016464,
-.015571,-.016064,
-.016064,-.015571,
-.016464,-.015,
-.016759,-.014368,
-.016939,-.013695,
-.017,-.013,
-.017,.013,
-.016939,.013695,
-.016759,.014368,
-.016464,.015,
-.016064,.015571,
-.015571,.016064,
-.015,.016464,
-.014368,.016759,
-.013695,.016939,
-.013,.017,
.013,.017,
.013695,.016939,
.014368,.016759,
.015,.016464,
.015571,.016064,
.016064,.015571,
.016464,.015,
.016759,.014368,
.016939,.013695,
.017,.013,
0.0*
%
%ADD43MACRO43*%
%ADD75R,.012X.06*%
%ADD67R,.016X.02*%
%ADD46R,.06X.014*%
%ADD28C,.13*%
%AMMACRO79*
4,1,40,.007,.004,
.007,-.004,
.00697,-.004347,
.006879,-.004684,
.006732,-.005,
.006532,-.005286,
.006286,-.005532,
.006,-.005732,
.005684,-.005879,
.005347,-.00597,
.005,-.006,
-.005,-.006,
-.005347,-.00597,
-.005684,-.005879,
-.006,-.005732,
-.006286,-.005532,
-.006532,-.005286,
-.006732,-.005,
-.006879,-.004684,
-.00697,-.004347,
-.007,-.004,
-.007,.004,
-.00697,.004347,
-.006879,.004684,
-.006732,.005,
-.006532,.005286,
-.006286,.005532,
-.006,.005732,
-.005684,.005879,
-.005347,.00597,
-.005,.006,
.005,.006,
.005347,.00597,
.005684,.005879,
.006,.005732,
.006286,.005532,
.006532,.005286,
.006732,.005,
.006879,.004684,
.00697,.004347,
.007,.004,
0.0*
%
%ADD79MACRO79*%
%AMMACRO76*
4,1,40,.004,-.007,
-.004,-.007,
-.004347,-.00697,
-.004684,-.006879,
-.005,-.006732,
-.005286,-.006532,
-.005532,-.006286,
-.005732,-.006,
-.005879,-.005684,
-.00597,-.005347,
-.006,-.005,
-.006,.005,
-.00597,.005347,
-.005879,.005684,
-.005732,.006,
-.005532,.006286,
-.005286,.006532,
-.005,.006732,
-.004684,.006879,
-.004347,.00697,
-.004,.007,
.004,.007,
.004347,.00697,
.004684,.006879,
.005,.006732,
.005286,.006532,
.005532,.006286,
.005732,.006,
.005879,.005684,
.00597,.005347,
.006,.005,
.006,-.005,
.00597,-.005347,
.005879,-.005684,
.005732,-.006,
.005532,-.006286,
.005286,-.006532,
.005,-.006732,
.004684,-.006879,
.004347,-.00697,
.004,-.007,
0.0*
%
%ADD76MACRO76*%
%ADD70C,.15*%
%ADD57R,.05X.065*%
%ADD51O,.06X.084*%
%ADD77R,.065X.05*%
%ADD14O,.268X.134*%
%ADD34R,.048X.016*%
%ADD21R,.045X.055*%
%ADD73C,.119*%
%ADD49R,.016X.048*%
%ADD39R,.055X.045*%
%ADD68R,.063X.039*%
%ADD48C,.256*%
%ADD13C,.375*%
%AMMACRO59*
4,1,40,-.014,.008,
-.014,-.008,
-.013939,-.008695,
-.013759,-.009368,
-.013464,-.01,
-.013064,-.010571,
-.012571,-.011064,
-.012,-.011464,
-.011368,-.011759,
-.010695,-.011939,
-.01,-.012,
.01,-.012,
.010695,-.011939,
.011368,-.011759,
.012,-.011464,
.012571,-.011064,
.013064,-.010571,
.013464,-.01,
.013759,-.009368,
.013939,-.008695,
.014,-.008,
.014,.008,
.013939,.008695,
.013759,.009368,
.013464,.01,
.013064,.010571,
.012571,.011064,
.012,.011464,
.011368,.011759,
.010695,.011939,
.01,.012,
-.01,.012,
-.010695,.011939,
-.011368,.011759,
-.012,.011464,
-.012571,.011064,
-.013064,.010571,
-.013464,.01,
-.013759,.009368,
-.013939,.008695,
-.014,.008,
0.0*
%
%ADD59MACRO59*%
%AMMACRO58*
4,1,40,-.0225,-.007,
-.022378,-.008389,
-.022018,-.009736,
-.021428,-.011,
-.020628,-.012142,
-.019642,-.013128,
-.0185,-.013928,
-.017236,-.014518,
-.015889,-.014878,
-.0145,-.015,
.0145,-.015,
.015889,-.014878,
.017236,-.014518,
.0185,-.013928,
.019642,-.013128,
.020628,-.012142,
.021428,-.011,
.022018,-.009736,
.022378,-.008389,
.0225,-.007,
.0225,.007,
.022378,.008389,
.022018,.009736,
.021428,.011,
.020628,.012142,
.019642,.013128,
.0185,.013928,
.017236,.014518,
.015889,.014878,
.0145,.015,
-.0145,.015,
-.015889,.014878,
-.017236,.014518,
-.0185,.013928,
-.019642,.013128,
-.020628,.012142,
-.021428,.011,
-.022018,.009736,
-.022378,.008389,
-.0225,.007,
-.0225,-.007,
0.0*
%
%ADD58MACRO58*%
%AMMACRO53*
4,1,40,-.007,.0225,
-.008389,.022378,
-.009736,.022018,
-.011,.021428,
-.012142,.020628,
-.013128,.019642,
-.013928,.0185,
-.014518,.017236,
-.014878,.015889,
-.015,.0145,
-.015,-.0145,
-.014878,-.015889,
-.014518,-.017236,
-.013928,-.0185,
-.013128,-.019642,
-.012142,-.020628,
-.011,-.021428,
-.009736,-.022018,
-.008389,-.022378,
-.007,-.0225,
.007,-.0225,
.008389,-.022378,
.009736,-.022018,
.011,-.021428,
.012142,-.020628,
.013128,-.019642,
.013928,-.0185,
.014518,-.017236,
.014878,-.015889,
.015,-.0145,
.015,.0145,
.014878,.015889,
.014518,.017236,
.013928,.0185,
.013128,.019642,
.012142,.020628,
.011,.021428,
.009736,.022018,
.008389,.022378,
.007,.0225,
-.007,.0225,
0.0*
%
%ADD53MACRO53*%
%AMMACRO30*
4,1,40,.012,.008,
.012,-.008,
.011939,-.008695,
.011759,-.009368,
.011464,-.01,
.011064,-.010571,
.010571,-.011064,
.01,-.011464,
.009368,-.011759,
.008695,-.011939,
.008,-.012,
-.008,-.012,
-.008695,-.011939,
-.009368,-.011759,
-.01,-.011464,
-.010571,-.011064,
-.011064,-.010571,
-.011464,-.01,
-.011759,-.009368,
-.011939,-.008695,
-.012,-.008,
-.012,.008,
-.011939,.008695,
-.011759,.009368,
-.011464,.01,
-.011064,.010571,
-.010571,.011064,
-.01,.011464,
-.009368,.011759,
-.008695,.011939,
-.008,.012,
.008,.012,
.008695,.011939,
.009368,.011759,
.01,.011464,
.010571,.011064,
.011064,.010571,
.011464,.01,
.011759,.009368,
.011939,.008695,
.012,.008,
0.0*
%
%ADD30MACRO30*%
%AMMACRO20*
4,1,40,.008,-.012,
-.008,-.012,
-.008695,-.011939,
-.009368,-.011759,
-.01,-.011464,
-.010571,-.011064,
-.011064,-.010571,
-.011464,-.01,
-.011759,-.009368,
-.011939,-.008695,
-.012,-.008,
-.012,.008,
-.011939,.008695,
-.011759,.009368,
-.011464,.01,
-.011064,.010571,
-.010571,.011064,
-.01,.011464,
-.009368,.011759,
-.008695,.011939,
-.008,.012,
.008,.012,
.008695,.011939,
.009368,.011759,
.01,.011464,
.010571,.011064,
.011064,.010571,
.011464,.01,
.011759,.009368,
.011939,.008695,
.012,.008,
.012,-.008,
.011939,-.008695,
.011759,-.009368,
.011464,-.01,
.011064,-.010571,
.010571,-.011064,
.01,-.011464,
.009368,-.011759,
.008695,-.011939,
.008,-.012,
0.0*
%
%ADD20MACRO20*%
%AMMACRO17*
4,1,40,-.007,.011,
.007,.011,
.007695,.010939,
.008368,.010759,
.009,.010464,
.009571,.010064,
.010064,.009571,
.010464,.009,
.010759,.008368,
.010939,.007695,
.011,.007,
.011,-.007,
.010939,-.007695,
.010759,-.008368,
.010464,-.009,
.010064,-.009571,
.009571,-.010064,
.009,-.010464,
.008368,-.010759,
.007695,-.010939,
.007,-.011,
-.007,-.011,
-.007695,-.010939,
-.008368,-.010759,
-.009,-.010464,
-.009571,-.010064,
-.010064,-.009571,
-.010464,-.009,
-.010759,-.008368,
-.010939,-.007695,
-.011,-.007,
-.011,.007,
-.010939,.007695,
-.010759,.008368,
-.010464,.009,
-.010064,.009571,
-.009571,.010064,
-.009,.010464,
-.008368,.010759,
-.007695,.010939,
-.007,.011,
0.0*
%
%ADD17MACRO17*%
%AMMACRO31*
4,1,40,.011,.007,
.011,-.007,
.010939,-.007695,
.010759,-.008368,
.010464,-.009,
.010064,-.009571,
.009571,-.010064,
.009,-.010464,
.008368,-.010759,
.007695,-.010939,
.007,-.011,
-.007,-.011,
-.007695,-.010939,
-.008368,-.010759,
-.009,-.010464,
-.009571,-.010064,
-.010064,-.009571,
-.010464,-.009,
-.010759,-.008368,
-.010939,-.007695,
-.011,-.007,
-.011,.007,
-.010939,.007695,
-.010759,.008368,
-.010464,.009,
-.010064,.009571,
-.009571,.010064,
-.009,.010464,
-.008368,.010759,
-.007695,.010939,
-.007,.011,
.007,.011,
.007695,.010939,
.008368,.010759,
.009,.010464,
.009571,.010064,
.010064,.009571,
.010464,.009,
.010759,.008368,
.010939,.007695,
.011,.007,
0.0*
%
%ADD31MACRO31*%
%AMMACRO78*
4,1,6,-.0135,-.025,
.0065,-.005,
.0135,-.005,
.0135,.005,
.0065,.005,
-.0135,.025,
-.0135,-.025,
0.0*
%
%ADD78MACRO78*%
%AMMACRO25*
4,1,40,.013,-.017,
-.013,-.017,
-.013695,-.016939,
-.014368,-.016759,
-.015,-.016464,
-.015571,-.016064,
-.016064,-.015571,
-.016464,-.015,
-.016759,-.014368,
-.016939,-.013695,
-.017,-.013,
-.017,.013,
-.016939,.013695,
-.016759,.014368,
-.016464,.015,
-.016064,.015571,
-.015571,.016064,
-.015,.016464,
-.014368,.016759,
-.013695,.016939,
-.013,.017,
.013,.017,
.013695,.016939,
.014368,.016759,
.015,.016464,
.015571,.016064,
.016064,.015571,
.016464,.015,
.016759,.014368,
.016939,.013695,
.017,.013,
.017,-.013,
.016939,-.013695,
.016759,-.014368,
.016464,-.015,
.016064,-.015571,
.015571,-.016064,
.015,-.016464,
.014368,-.016759,
.013695,-.016939,
.013,-.017,
0.0*
%
%ADD25MACRO25*%
%AMMACRO23*
4,1,40,-.017,-.013,
-.017,.013,
-.016939,.013695,
-.016759,.014368,
-.016464,.015,
-.016064,.015571,
-.015571,.016064,
-.015,.016464,
-.014368,.016759,
-.013695,.016939,
-.013,.017,
.013,.017,
.013695,.016939,
.014368,.016759,
.015,.016464,
.015571,.016064,
.016064,.015571,
.016464,.015,
.016759,.014368,
.016939,.013695,
.017,.013,
.017,-.013,
.016939,-.013695,
.016759,-.014368,
.016464,-.015,
.016064,-.015571,
.015571,-.016064,
.015,-.016464,
.014368,-.016759,
.013695,-.016939,
.013,-.017,
-.013,-.017,
-.013695,-.016939,
-.014368,-.016759,
-.015,-.016464,
-.015571,-.016064,
-.016064,-.015571,
-.016464,-.015,
-.016759,-.014368,
-.016939,-.013695,
-.017,-.013,
0.0*
%
%ADD23MACRO23*%
%AMMACRO29*
4,1,40,.012,.008,
.012,-.008,
.011939,-.008695,
.011759,-.009368,
.011464,-.01,
.011064,-.010571,
.010571,-.011064,
.01,-.011464,
.009368,-.011759,
.008695,-.011939,
.008,-.012,
-.008,-.012,
-.008695,-.011939,
-.009368,-.011759,
-.01,-.011464,
-.010571,-.011064,
-.011064,-.010571,
-.011464,-.01,
-.011759,-.009368,
-.011939,-.008695,
-.012,-.008,
-.012,.008,
-.011939,.008695,
-.011759,.009368,
-.011464,.01,
-.011064,.010571,
-.010571,.011064,
-.01,.011464,
-.009368,.011759,
-.008695,.011939,
-.008,.012,
.008,.012,
.008695,.011939,
.009368,.011759,
.01,.011464,
.010571,.011064,
.011064,.010571,
.011464,.01,
.011759,.009368,
.011939,.008695,
.012,.008,
0.0*
%
%ADD29MACRO29*%
%AMMACRO19*
4,1,40,.008,-.012,
-.008,-.012,
-.008695,-.011939,
-.009368,-.011759,
-.01,-.011464,
-.010571,-.011064,
-.011064,-.010571,
-.011464,-.01,
-.011759,-.009368,
-.011939,-.008695,
-.012,-.008,
-.012,.008,
-.011939,.008695,
-.011759,.009368,
-.011464,.01,
-.011064,.010571,
-.010571,.011064,
-.01,.011464,
-.009368,.011759,
-.008695,.011939,
-.008,.012,
.008,.012,
.008695,.011939,
.009368,.011759,
.01,.011464,
.010571,.011064,
.011064,.010571,
.011464,.01,
.011759,.009368,
.011939,.008695,
.012,.008,
.012,-.008,
.011939,-.008695,
.011759,-.009368,
.011464,-.01,
.011064,-.010571,
.010571,-.011064,
.01,-.011464,
.009368,-.011759,
.008695,-.011939,
.008,-.012,
0.0*
%
%ADD19MACRO19*%
%AMMACRO18*
4,1,40,-.007,.011,
.007,.011,
.007695,.010939,
.008368,.010759,
.009,.010464,
.009571,.010064,
.010064,.009571,
.010464,.009,
.010759,.008368,
.010939,.007695,
.011,.007,
.011,-.007,
.010939,-.007695,
.010759,-.008368,
.010464,-.009,
.010064,-.009571,
.009571,-.010064,
.009,-.010464,
.008368,-.010759,
.007695,-.010939,
.007,-.011,
-.007,-.011,
-.007695,-.010939,
-.008368,-.010759,
-.009,-.010464,
-.009571,-.010064,
-.010064,-.009571,
-.010464,-.009,
-.010759,-.008368,
-.010939,-.007695,
-.011,-.007,
-.011,.007,
-.010939,.007695,
-.010759,.008368,
-.010464,.009,
-.010064,.009571,
-.009571,.010064,
-.009,.010464,
-.008368,.010759,
-.007695,.010939,
-.007,.011,
0.0*
%
%ADD18MACRO18*%
%ADD82C,.006*%
G75*
%LPD*%
G75*
G54D10*
G01X-13131Y-65072D02*
Y-145072D01*
G01D02*
X1244069D01*
G01X-29131Y-65072D02*
Y-33072D01*
G01X-13131Y-65072D02*
X1244069D01*
G01X-13131Y-100572D02*
X1244069D01*
G01X-17131Y-49072D02*
G02I-12000J0D01*
G01X-22281D02*
G02I-6850J0D01*
G01X-13131D02*
X-45131D01*
G01X456569Y-65072D02*
Y-145072D01*
G01X594069Y-65072D02*
Y-145072D01*
G01X709069Y-65072D02*
Y-145072D01*
G01X876569Y-65072D02*
Y-145072D01*
G01X1046569Y-65072D02*
Y-145072D01*
G01X1244069Y-65072D02*
Y-145072D01*
G01X1272069Y-49072D02*
G02I-12000J0D01*
G01X1266919D02*
G02I-6850J0D01*
G01X1276069D02*
X1244069D01*
G01X1260069Y-65072D02*
Y-33072D01*
X8500Y18279D03*
Y28279D03*
Y38279D03*
Y48279D03*
Y58279D03*
Y68279D03*
X13721Y8500D03*
X8500Y13279D03*
Y23279D03*
Y33279D03*
Y43279D03*
Y53279D03*
Y63279D03*
Y78279D03*
Y88279D03*
Y98279D03*
Y108279D03*
Y118279D03*
Y128279D03*
Y73279D03*
Y83279D03*
Y93279D03*
Y103279D03*
Y113279D03*
Y123279D03*
Y133279D03*
Y138279D03*
Y148279D03*
Y158279D03*
Y168279D03*
Y178279D03*
Y188279D03*
Y198279D03*
Y143279D03*
Y153279D03*
Y163279D03*
Y173279D03*
Y183279D03*
Y193279D03*
Y208279D03*
Y218279D03*
Y228279D03*
Y238279D03*
Y248279D03*
Y258279D03*
Y203279D03*
Y213279D03*
Y223279D03*
Y233279D03*
Y243279D03*
Y253279D03*
Y263279D03*
Y268279D03*
Y278279D03*
Y288279D03*
Y298279D03*
Y308279D03*
Y318279D03*
Y328279D03*
Y273279D03*
Y283279D03*
Y293279D03*
Y303279D03*
Y313279D03*
Y323279D03*
Y338279D03*
Y348279D03*
Y358279D03*
Y368279D03*
Y378279D03*
Y388279D03*
Y333279D03*
Y343279D03*
Y353279D03*
Y363279D03*
Y373279D03*
Y383279D03*
Y393279D03*
Y398279D03*
Y408279D03*
Y418279D03*
Y428279D03*
Y438279D03*
Y448279D03*
Y458279D03*
Y403279D03*
Y413279D03*
Y423279D03*
Y433279D03*
Y443279D03*
Y453279D03*
Y468279D03*
Y478279D03*
Y488279D03*
Y498279D03*
Y508279D03*
Y518279D03*
Y528279D03*
Y463279D03*
Y473279D03*
Y483279D03*
Y493279D03*
Y503279D03*
Y513279D03*
Y523279D03*
Y538279D03*
Y548279D03*
Y558279D03*
Y568279D03*
Y578279D03*
Y588279D03*
Y533279D03*
Y543279D03*
Y553279D03*
Y563279D03*
Y573279D03*
Y583279D03*
Y593279D03*
Y598279D03*
Y608279D03*
Y618279D03*
Y628279D03*
Y638279D03*
Y648279D03*
Y658279D03*
Y603279D03*
Y613279D03*
Y623279D03*
Y633279D03*
Y643279D03*
Y653279D03*
Y668279D03*
Y678279D03*
Y688279D03*
Y698279D03*
Y708279D03*
Y718279D03*
Y663279D03*
Y673279D03*
Y683279D03*
Y693279D03*
Y703279D03*
Y713279D03*
X8892Y723187D03*
X11090Y727806D03*
X13500Y732400D03*
X78721Y8500D03*
X68721D03*
X58721D03*
X48721D03*
X38721D03*
X28721D03*
X18721D03*
X73721D03*
X53721D03*
X43721D03*
X33721D03*
X23721D03*
X63721D03*
X75534Y625175D03*
X75300Y679300D03*
Y674300D03*
X78370Y724300D03*
Y719500D03*
X28100Y755600D03*
X33100D03*
X69057Y755280D03*
X74057D03*
X20300Y746200D03*
X15800Y736900D03*
X18100Y741500D03*
X22600Y750800D03*
X79057Y755280D03*
X108721Y8500D03*
X98721D03*
X88721D03*
X112197Y65406D03*
Y60406D03*
Y55406D03*
X103721Y8500D03*
X93721D03*
X83721D03*
X112197Y75406D03*
Y85406D03*
Y95406D03*
Y105406D03*
Y115406D03*
Y120406D03*
Y110406D03*
Y100406D03*
Y90406D03*
Y80406D03*
Y70406D03*
Y145406D03*
Y195406D03*
Y185406D03*
Y175406D03*
Y165406D03*
Y155406D03*
Y200406D03*
Y190406D03*
Y180406D03*
Y170406D03*
Y160406D03*
Y150406D03*
Y265406D03*
Y255406D03*
Y245406D03*
Y235406D03*
Y225406D03*
Y215406D03*
Y205406D03*
Y260406D03*
Y250406D03*
Y240406D03*
Y230406D03*
Y220406D03*
Y210406D03*
Y325406D03*
Y315406D03*
Y305406D03*
Y295406D03*
Y285406D03*
Y275406D03*
Y330406D03*
Y320406D03*
Y310406D03*
Y300406D03*
Y290406D03*
Y280406D03*
Y270406D03*
Y390406D03*
Y380406D03*
Y370406D03*
Y360406D03*
Y350406D03*
Y395406D03*
Y385406D03*
Y375406D03*
Y365406D03*
Y355406D03*
Y345406D03*
Y335406D03*
Y340406D03*
Y420406D03*
Y410406D03*
Y400406D03*
Y425406D03*
Y415406D03*
Y405406D03*
X103600Y637800D03*
X103500Y645500D03*
Y650535D03*
X80334Y625175D03*
X99600Y673500D03*
Y678500D03*
X86500Y703100D03*
X86600Y708300D03*
X96800Y662000D03*
X90200Y667100D03*
X85400D03*
X99600Y683500D03*
X81300Y675100D03*
Y680100D03*
X134223Y691027D03*
X83170Y724300D03*
Y719500D03*
X122435Y666782D03*
Y661982D03*
X144057Y755280D03*
X134057D03*
X124057D03*
X114057D03*
X104057D03*
X94057D03*
X84057D03*
X89057D03*
X99057D03*
X109057D03*
X119057D03*
X129057D03*
X139057D03*
X91700Y744800D03*
X96500D03*
X101300D03*
X106100D03*
X110900D03*
X115700D03*
X120500D03*
X125300D03*
X208300Y704985D03*
X203500D03*
X198700D03*
X193900D03*
X155400Y717700D03*
X204057Y755280D03*
X194057D03*
X184057D03*
X174057D03*
X164057D03*
X154057D03*
X149057D03*
X159057D03*
X169057D03*
X179057D03*
X189057D03*
X199057D03*
X209057D03*
X222700Y704985D03*
X217900D03*
X213100D03*
X249500Y719500D03*
Y724300D03*
X274057Y755280D03*
X264057D03*
X254057D03*
X244057D03*
X234057D03*
X224057D03*
X214057D03*
X219057D03*
X229057D03*
X239057D03*
X249057D03*
X259057D03*
X269057D03*
X249500Y729100D03*
Y733900D03*
Y738700D03*
X315120Y8500D03*
X310120D03*
X305120D03*
X300120D03*
X296020Y9420D03*
Y14420D03*
Y19420D03*
Y24420D03*
Y29420D03*
X321382Y197574D03*
X296282Y189224D03*
Y184424D03*
X301082D03*
Y189224D03*
X335132Y195874D03*
X305862Y210014D03*
X334882Y215874D03*
Y220874D03*
X321382Y202374D03*
X335132Y205974D03*
X335200Y640100D03*
X330400D03*
X335000Y615400D03*
X335300Y609800D03*
X335000Y621200D03*
X325600Y640100D03*
X322586Y653754D03*
X317786D03*
X312986D03*
X308186D03*
X330200Y709300D03*
X334650Y689700D03*
X335350Y684650D03*
X315520Y711720D03*
X325700Y711600D03*
X320320Y711720D03*
X305500Y721000D03*
X310500D03*
X304150Y674700D03*
X299350D03*
X334057Y755280D03*
X324057D03*
X314057D03*
X304057D03*
X294057D03*
X284057D03*
X279057D03*
X289057D03*
X299057D03*
X309057D03*
X319057D03*
X329057D03*
X339057D03*
X305500Y726000D03*
X310500D03*
X381638Y755280D03*
X384809Y752321D03*
X387045Y747849D03*
X389281Y743376D03*
X391517Y738904D03*
X393753Y734432D03*
X395989Y729960D03*
X398225Y725488D03*
X344057Y755280D03*
X521634Y38901D03*
Y34101D03*
X516834Y38901D03*
Y34101D03*
X526434Y43701D03*
X521634D03*
X516834D03*
X520000Y63400D03*
X515200Y66440D03*
X520585Y68348D03*
X536794Y77373D03*
X531664Y78463D03*
X515915Y80576D03*
X520310Y76700D03*
X508668Y79607D03*
X503550Y79500D03*
X511100Y75060D03*
X506100D03*
X511100Y70060D03*
X525200Y71440D03*
X516628Y71806D03*
X600700Y35700D03*
X595500Y35600D03*
X595700Y29800D03*
X600900Y29700D03*
X576610Y388416D03*
Y393416D03*
X576512Y369625D03*
Y364825D03*
X581312Y369625D03*
Y364825D03*
X576610Y398416D03*
Y403416D03*
Y408416D03*
Y413416D03*
Y418416D03*
Y423416D03*
Y428416D03*
Y433416D03*
Y438416D03*
Y443416D03*
Y448416D03*
Y453416D03*
Y458416D03*
Y463416D03*
Y468416D03*
Y473416D03*
Y478416D03*
Y483416D03*
Y488416D03*
Y493416D03*
Y498416D03*
Y503416D03*
Y508416D03*
Y513416D03*
Y518416D03*
Y523416D03*
Y528416D03*
Y533416D03*
Y538416D03*
Y543416D03*
Y548416D03*
Y553416D03*
Y558416D03*
Y563416D03*
Y568416D03*
Y573416D03*
Y578416D03*
Y583416D03*
Y588416D03*
Y593416D03*
Y598416D03*
Y603416D03*
Y608416D03*
Y613416D03*
Y618416D03*
Y623416D03*
Y628416D03*
Y633416D03*
Y638416D03*
Y643416D03*
Y648416D03*
Y653416D03*
Y658416D03*
Y663416D03*
Y668416D03*
Y673416D03*
Y678416D03*
Y683416D03*
Y688416D03*
Y693416D03*
Y698416D03*
Y703416D03*
Y708416D03*
Y713416D03*
Y718416D03*
X577063Y723309D03*
X579299Y727781D03*
X581535Y732253D03*
X583771Y736725D03*
X586007Y741198D03*
X588243Y745670D03*
X590479Y750142D03*
X592715Y754614D03*
X609200Y330400D03*
X658000Y431500D03*
Y409000D03*
Y414000D03*
Y426000D03*
Y420500D03*
X642700Y454400D03*
X642500Y449100D03*
X642600Y459500D03*
X610000Y467500D03*
X609000Y473500D03*
Y478500D03*
Y483500D03*
X645200Y521900D03*
X650400Y517600D03*
X656400Y517500D03*
X661500Y517600D03*
X621600Y486619D03*
X626958Y486419D03*
X642500Y464700D03*
X629500Y482500D03*
Y477000D03*
Y471500D03*
X635000Y482500D03*
Y476500D03*
Y471000D03*
X615500Y529800D03*
X616710Y534500D03*
X657000Y555000D03*
X662000D03*
X661887Y560010D03*
X656887D03*
X645300Y655200D03*
Y650400D03*
Y645600D03*
Y640800D03*
X655000Y705000D03*
Y700200D03*
Y695400D03*
Y690600D03*
X645300Y684000D03*
Y679200D03*
Y674400D03*
Y669600D03*
Y664800D03*
Y660000D03*
X655000Y685800D03*
X659722Y755280D03*
X649722D03*
X639722D03*
X634722D03*
X644722D03*
X654722D03*
X664722D03*
X708483Y311988D03*
X713283D03*
X723900Y326350D03*
X718940Y326270D03*
X714900Y453600D03*
X715200Y459600D03*
X706700Y413900D03*
X710200Y417400D03*
Y422900D03*
Y427900D03*
X698700Y417600D03*
Y423100D03*
Y428100D03*
X676000Y431000D03*
X671000D03*
Y421000D03*
X676000D03*
X671000Y426000D03*
X676000D03*
X715200Y465000D03*
X689500Y518500D03*
Y524000D03*
X694738Y523940D03*
X694690Y519034D03*
X670400Y565500D03*
Y560700D03*
Y555900D03*
Y551100D03*
Y546300D03*
Y541500D03*
Y536700D03*
X687015Y658100D03*
Y653300D03*
Y648500D03*
Y643700D03*
Y682100D03*
X673950Y686104D03*
Y691104D03*
Y696104D03*
Y701104D03*
Y706104D03*
X687015Y677300D03*
Y672500D03*
Y667700D03*
Y662900D03*
X729722Y755280D03*
X719722D03*
X709722D03*
X699722D03*
X689722D03*
X679722D03*
X669722D03*
X674722D03*
X684722D03*
X694722D03*
X704722D03*
X714722D03*
X724722D03*
X734722D03*
X780100Y8500D03*
X775100D03*
X770100D03*
X765100D03*
X760100D03*
X755100D03*
X750100D03*
X745100D03*
X787895D03*
X797895D03*
X792895D03*
X754000Y172700D03*
Y177500D03*
X798359Y351659D03*
X795193Y355540D03*
X791786Y359001D03*
X735484Y429378D03*
Y434178D03*
Y462978D03*
Y458178D03*
Y453378D03*
Y448578D03*
Y443778D03*
Y438978D03*
X798000Y459300D03*
X740300Y427100D03*
Y431900D03*
X751100Y405400D03*
X755900D03*
X760700D03*
X765500D03*
X770300D03*
X775100D03*
X740300Y446300D03*
Y441500D03*
Y436700D03*
X790600Y458000D03*
X781000D03*
X785800D03*
X776200D03*
X789500Y405400D03*
X784700D03*
X779900D03*
X750000Y427100D03*
X754800D03*
X783800Y436000D03*
X779000D03*
X793400D03*
X788600D03*
X788400Y427100D03*
X783600D03*
X778800D03*
X774200Y436000D03*
X774000Y427100D03*
X769200D03*
X764400D03*
X759600D03*
X735484Y467778D03*
X799722Y755280D03*
X789722D03*
X779722D03*
X769722D03*
X759722D03*
X749722D03*
X739722D03*
X744722D03*
X754722D03*
X764722D03*
X774722D03*
X784722D03*
X794722D03*
X807895Y8500D03*
X817895D03*
X827895D03*
X837895D03*
X847895D03*
X857895D03*
X862895D03*
X852895D03*
X842895D03*
X832895D03*
X822895D03*
X812895D03*
X802895D03*
X842600Y339400D03*
X841100Y332300D03*
X826993Y358840D03*
X821502Y358356D03*
X827145Y363638D03*
X821653Y363488D03*
X826900Y332500D03*
X825300Y339900D03*
X825100Y347300D03*
X828100Y352900D03*
X809792Y379122D03*
X814592D03*
X809792Y374322D03*
X814592D03*
X842900Y347200D03*
X840800Y352800D03*
X828000Y459300D03*
X823200D03*
X832800D03*
X818400D03*
X807600D03*
X802800D03*
X812400D03*
X864727Y398458D03*
X804300Y436500D03*
X813900D03*
X809100D03*
X818700D03*
X823500D03*
X830100Y501500D03*
X839700D03*
X834900D03*
X827000Y516000D03*
X832000D03*
Y521000D03*
X827000D03*
X843900Y464000D03*
X848700Y465200D03*
Y470600D03*
X849722Y755280D03*
X839722D03*
X829722D03*
X819722D03*
X809722D03*
X804722D03*
X814722D03*
X824722D03*
X834722D03*
X844722D03*
X854722D03*
X867895Y8500D03*
X877895D03*
X887895D03*
X897895D03*
X907895D03*
X916697Y19698D03*
Y29698D03*
Y39698D03*
Y49698D03*
Y59698D03*
Y69698D03*
Y64698D03*
Y54698D03*
Y44698D03*
Y34698D03*
Y24698D03*
Y14698D03*
X912895Y8500D03*
X902895D03*
X892895D03*
X882895D03*
X872895D03*
X916697Y79698D03*
Y89698D03*
Y99698D03*
Y109698D03*
Y119698D03*
Y129698D03*
Y134698D03*
Y124698D03*
Y114698D03*
Y104698D03*
Y94698D03*
Y84698D03*
Y74698D03*
Y139698D03*
Y149698D03*
Y159698D03*
Y169698D03*
Y179698D03*
Y189698D03*
Y199698D03*
Y194698D03*
Y184698D03*
Y174698D03*
Y164698D03*
Y154698D03*
Y144698D03*
Y209698D03*
Y219698D03*
Y229698D03*
Y239698D03*
Y249698D03*
Y259698D03*
Y264698D03*
Y254698D03*
Y244698D03*
Y234698D03*
Y224698D03*
Y214698D03*
Y204698D03*
Y269698D03*
Y279698D03*
Y289698D03*
Y299698D03*
Y309698D03*
Y319698D03*
Y329698D03*
Y324698D03*
Y314698D03*
Y304698D03*
Y294698D03*
Y284698D03*
Y274698D03*
Y339698D03*
Y349698D03*
Y359698D03*
Y369698D03*
Y379698D03*
Y389698D03*
Y394698D03*
Y384698D03*
Y374698D03*
Y364698D03*
Y354698D03*
Y344698D03*
Y334698D03*
X881147Y394517D03*
X916697Y399698D03*
Y409698D03*
Y419698D03*
Y429698D03*
Y439698D03*
Y449698D03*
Y459698D03*
Y454698D03*
Y444698D03*
Y434698D03*
Y424698D03*
Y414698D03*
Y404698D03*
X874727Y398458D03*
X869727D03*
X880887Y399474D03*
X916697Y469698D03*
Y479698D03*
Y489698D03*
Y499698D03*
Y509698D03*
Y519698D03*
Y524698D03*
Y514698D03*
Y504698D03*
Y494698D03*
Y484698D03*
Y474698D03*
Y464698D03*
Y529698D03*
Y539698D03*
Y549698D03*
Y559698D03*
Y569698D03*
Y579698D03*
Y589698D03*
Y584698D03*
Y574698D03*
Y564698D03*
Y554698D03*
Y544698D03*
Y534698D03*
Y599698D03*
Y609698D03*
Y619698D03*
Y629698D03*
Y639698D03*
Y649698D03*
Y659698D03*
Y654698D03*
Y644698D03*
Y634698D03*
Y624698D03*
Y614698D03*
Y604698D03*
Y594698D03*
Y669698D03*
Y679698D03*
Y689698D03*
Y699698D03*
Y709698D03*
Y719698D03*
Y714698D03*
Y704698D03*
Y694698D03*
Y684698D03*
Y674698D03*
Y664698D03*
X914700Y726100D03*
X912436Y730603D03*
X910200Y735300D03*
X907564Y739747D03*
X905500Y744400D03*
X903192Y748791D03*
X900800Y753700D03*
X894722Y755280D03*
G54D20*
X65400Y549600D03*
X78231Y565999D03*
X92870Y568015D03*
X97113Y567986D03*
X100619Y567985D03*
X137100Y595600D03*
X133600D03*
X207500Y499180D03*
X252670Y624037D03*
X224346Y625595D03*
X245200Y691900D03*
X365400Y511600D03*
X367600Y705500D03*
X645000Y556500D03*
X721400Y281800D03*
X790360Y243000D03*
G54D11*
X80708Y44292D03*
X61024Y34449D03*
X33464D03*
X56102Y24606D03*
X38386D03*
X108268Y44292D03*
X103346Y34449D03*
X85630D03*
X590300Y574400D03*
X600300D03*
X610300D03*
G54D30*
X110300Y497300D03*
X162335Y481762D03*
X148716Y570304D03*
X171979Y583387D03*
X175660Y611180D03*
Y607480D03*
X203750Y633450D03*
X263205Y549594D03*
X232800Y633900D03*
X356000Y541400D03*
X365489Y554000D03*
X557200Y64700D03*
X581000Y77400D03*
X662200Y421500D03*
Y417500D03*
Y413500D03*
Y426000D03*
X723668Y294464D03*
X731168D03*
X787150Y234770D03*
X753500Y262350D03*
X787300Y224400D03*
X787150Y231350D03*
Y227900D03*
X746000Y262350D03*
X744650Y268900D03*
X738668Y294464D03*
X752450Y268900D03*
G54D21*
X54100Y586350D03*
X46500D03*
X100100Y705700D03*
X92500D03*
X184910Y622020D03*
X192510D03*
X178430Y621990D03*
X170830D03*
X219840Y615320D03*
X227440D03*
X328622Y184294D03*
X321022D03*
X328648Y191994D03*
X321048D03*
X310449Y221407D03*
X318049D03*
X310479Y229157D03*
X318079D03*
X664600Y301300D03*
X622300Y481000D03*
X614700D03*
X622300Y473000D03*
X614700D03*
X731600Y261150D03*
X672200Y301300D03*
X721300Y456900D03*
X728900D03*
X721300Y464700D03*
X728900D03*
X697376Y554429D03*
X704976D03*
X781600Y196000D03*
X774000D03*
X795837Y196018D03*
X788237D03*
X761300Y199300D03*
X753700D03*
X761300Y191500D03*
X753700D03*
X773700Y188200D03*
X781300D03*
X788237Y188218D03*
X795837D03*
X758800Y174900D03*
X766400D03*
X772610Y241950D03*
X780210D03*
X739200Y261150D03*
X810162Y195983D03*
X802562D03*
Y188083D03*
X810162D03*
X830200Y339000D03*
X837800D03*
Y347000D03*
X830200D03*
X835600Y481500D03*
X843200D03*
G54D12*
X18700Y54650D03*
X209189Y37075D03*
Y383483D03*
X489331Y245605D03*
Y698924D03*
X901000Y21400D03*
X902500Y676000D03*
G54D31*
X140702Y489161D03*
X183100Y503100D03*
X179200Y525000D03*
X170800Y503100D03*
X179000D03*
X155000Y496400D03*
X166700Y503100D03*
X187300Y503000D03*
X166861Y490920D03*
X146300Y496100D03*
X150500Y496380D03*
X191000Y532600D03*
X202700Y532700D03*
X206800Y532580D03*
X205020Y608740D03*
X197191Y633188D03*
X192911Y633248D03*
X215658Y483533D03*
X266816Y561137D03*
X270836Y561119D03*
X246145Y557918D03*
X273490Y584402D03*
X228102Y529442D03*
X210900Y532600D03*
X335962Y702196D03*
X352480Y586164D03*
X365400Y572700D03*
X360300Y558400D03*
X347500Y706300D03*
X345654Y696615D03*
X375500Y704300D03*
X456400Y54400D03*
X512290Y54273D03*
X500411Y51865D03*
X490653Y60737D03*
X629500Y190800D03*
X656665Y298466D03*
X652465Y298566D03*
X732230Y307869D03*
X708300Y449300D03*
X750600Y488900D03*
X828800Y235900D03*
X815726Y363856D03*
G54D13*
X70865Y98425D03*
Y472440D03*
X49213Y740157D03*
X314960Y472440D03*
X405511Y39370D03*
X364173Y740157D03*
X612204Y433070D03*
Y740157D03*
X875985Y59055D03*
X875984Y433070D03*
Y740157D03*
G54D40*
X105474Y535824D03*
X181148Y568251D03*
X192089Y582625D03*
X185200Y559200D03*
X190680Y615540D03*
X222550Y609150D03*
X384614Y629080D03*
X836800Y332500D03*
G54D22*
X78524Y558398D03*
X78525Y554363D03*
X117930Y499550D03*
X98076Y560166D03*
X98044Y555240D03*
X149700Y460200D03*
X158530Y510140D03*
X173900Y517000D03*
X149565Y481057D03*
X149685Y468562D03*
X153988Y522134D03*
X153958Y517677D03*
X172402Y574058D03*
X148354Y588802D03*
X197490Y611700D03*
X169493Y635303D03*
X196760Y599340D03*
X184250Y607360D03*
X203790Y637250D03*
X197916Y620590D03*
X148057Y602562D03*
X224409Y558053D03*
X265912Y583809D03*
X224300Y585900D03*
X224375Y576816D03*
X224000Y571900D03*
X223200Y593200D03*
X243400Y531240D03*
X242200Y543100D03*
X245800Y606260D03*
X238150Y610860D03*
X211700Y642200D03*
X246365Y594250D03*
X235362Y606422D03*
X223200Y597200D03*
X232800Y637900D03*
X235410Y602160D03*
X232800Y642300D03*
X222092Y642006D03*
X317300Y552900D03*
X312700Y573000D03*
X308950Y658050D03*
X316500Y658100D03*
X338200Y696100D03*
X344117Y575841D03*
X356096Y545220D03*
X363600Y540600D03*
X375716Y620503D03*
X362500Y664200D03*
X375757Y695203D03*
X489779Y30448D03*
X507300Y65000D03*
X489800Y38500D03*
X479900Y58900D03*
Y62900D03*
X613286Y367271D03*
X707652Y261999D03*
X745700Y208500D03*
X821300Y240200D03*
X820100Y248200D03*
X821268Y235964D03*
X821300Y244200D03*
X811000Y257800D03*
X814500Y310400D03*
X832300Y353000D03*
G54D23*
X64350Y582500D03*
X129100Y597100D03*
X141189Y596337D03*
X209445Y525049D03*
X148840Y555135D03*
X153495Y555166D03*
X228384Y627209D03*
X375600Y604200D03*
X349200Y637700D03*
X354000D03*
X685700Y309600D03*
X690620Y323740D03*
X697200Y547900D03*
X706506Y603099D03*
X794726Y368356D03*
X759900Y492400D03*
G54D14*
X89764Y238386D03*
X309252Y413583D03*
G54D41*
X99874Y535824D03*
X175548Y568251D03*
X186489Y582625D03*
X179600Y559200D03*
X185080Y615540D03*
X216950Y609150D03*
X379014Y629080D03*
X831200Y332500D03*
G54D50*
X339331Y49803D03*
X360669Y91929D03*
G54D32*
X140702Y492561D03*
X183100Y506500D03*
X170800D03*
X179000D03*
X155000Y499800D03*
X166700Y506500D03*
X187300Y506400D03*
X166861Y494320D03*
X146300Y499500D03*
X150500Y499780D03*
X179200Y528400D03*
X191000Y536000D03*
X202700Y536100D03*
X206800Y535980D03*
X205020Y612140D03*
X197191Y636588D03*
X192911Y636648D03*
X215658Y486933D03*
X266816Y564537D03*
X270836Y564519D03*
X246145Y561318D03*
X273490Y587802D03*
X228102Y532842D03*
X210900Y536000D03*
X335962Y705596D03*
X352480Y589564D03*
X365400Y576100D03*
X360300Y561800D03*
X347500Y709700D03*
X345654Y700015D03*
X375500Y707700D03*
X456400Y57800D03*
X512290Y57673D03*
X500411Y55265D03*
X490653Y64137D03*
X629500Y194200D03*
X656665Y301866D03*
X652465Y301966D03*
X732230Y311269D03*
X708300Y452700D03*
X750600Y492300D03*
X828800Y239300D03*
X815726Y367256D03*
G54D51*
X339331Y91929D03*
X360669Y49803D03*
G54D33*
X121330Y499550D03*
X81924Y558398D03*
X81925Y554363D03*
X101476Y560166D03*
X101444Y555240D03*
X153100Y460200D03*
X161930Y510140D03*
X177300Y517000D03*
X152965Y481057D03*
X153085Y468562D03*
X157388Y522134D03*
X157358Y517677D03*
X175802Y574058D03*
X151754Y588802D03*
X200890Y611700D03*
X172893Y635303D03*
X200160Y599340D03*
X187650Y607360D03*
X207190Y637250D03*
X201316Y620590D03*
X151457Y602562D03*
X227809Y558053D03*
X269312Y583809D03*
X227700Y585900D03*
X227775Y576816D03*
X227400Y571900D03*
X226600Y593200D03*
X246800Y531240D03*
X245600Y543100D03*
X249200Y606260D03*
X241550Y610860D03*
X215100Y642200D03*
X249765Y594250D03*
X238762Y606422D03*
X226600Y597200D03*
X236200Y637900D03*
X238810Y602160D03*
X236200Y642300D03*
X225492Y642006D03*
X320700Y552900D03*
X316100Y573000D03*
X312350Y658050D03*
X319900Y658100D03*
X347517Y575841D03*
X359496Y545220D03*
X367000Y540600D03*
X379116Y620503D03*
X365900Y664200D03*
X341600Y696100D03*
X379157Y695203D03*
X493179Y30448D03*
X510700Y65000D03*
X493200Y38500D03*
X483300Y58900D03*
Y62900D03*
X616686Y367271D03*
X711052Y261999D03*
X749100Y208500D03*
X824700Y240200D03*
X823500Y248200D03*
X824668Y235964D03*
X824700Y244200D03*
X814400Y257800D03*
X817900Y310400D03*
X835700Y353000D03*
G54D42*
X141887Y560491D03*
X144037Y549486D03*
X204700Y519400D03*
X195400Y519500D03*
X200055Y519351D03*
X146567Y560391D03*
X151257Y560423D03*
X181505Y575791D03*
X160964Y717468D03*
X214100Y519500D03*
X445900Y31900D03*
X507895Y54797D03*
X496000Y50615D03*
X706580Y316040D03*
G54D15*
X75373Y509879D03*
X75405Y517477D03*
X69878Y509777D03*
X69778Y517477D03*
X64251Y509877D03*
X64151Y517477D03*
X97900Y510000D03*
X92286Y517477D03*
X81032D03*
X97913D03*
X92273Y510000D03*
X81068Y509866D03*
X86673Y510000D03*
X86659Y517477D03*
X136702Y492561D03*
X127800Y618100D03*
X174900Y506500D03*
X191869Y506489D03*
X167000Y520500D03*
X199892Y503022D03*
X162800Y494300D03*
X162700Y520500D03*
X171200Y525800D03*
X186111Y520181D03*
X182600Y536000D03*
X145400D03*
X198600Y536200D03*
X186900Y536100D03*
X178600Y535800D03*
X174500D03*
X159300Y529700D03*
X156501Y564267D03*
X196890Y567300D03*
X200910Y563190D03*
X150067Y614143D03*
X266800Y575100D03*
X270947Y576404D03*
X228400Y567750D03*
X238100Y586400D03*
X215100Y536000D03*
X242100Y586400D03*
X219200Y536500D03*
X232500Y529200D03*
X242000Y594200D03*
X327174Y389318D03*
X310700Y562600D03*
X315290Y681870D03*
X349182Y381274D03*
X345244Y587260D03*
X369500Y576100D03*
X351900Y532300D03*
X380000Y601800D03*
X634000Y194200D03*
X730900Y194700D03*
X670200Y203300D03*
X768529Y199354D03*
X740100Y491484D03*
X735600D03*
X744600D03*
X806100Y225900D03*
X802100D03*
X818100D03*
X814100D03*
X810100D03*
G54D60*
X367113Y622707D03*
Y626307D03*
X718590Y319060D03*
Y322660D03*
X726350Y319080D03*
Y322680D03*
X722390Y319060D03*
Y322660D03*
G54D24*
X64350Y576900D03*
X129100Y591500D03*
X141189Y590737D03*
X209445Y519449D03*
X148840Y549535D03*
X153495Y549566D03*
X228384Y621609D03*
X375600Y598600D03*
X349200Y632100D03*
X354000D03*
X685700Y304000D03*
X690620Y318140D03*
X697200Y542300D03*
X706506Y597499D03*
X794726Y362756D03*
X759900Y486800D03*
G54D25*
X49250Y580250D03*
X41868Y567316D03*
X96900Y712200D03*
X190450Y559250D03*
X194459Y577497D03*
X197030Y583440D03*
X185130Y552000D03*
X174460Y615380D03*
X694099Y607558D03*
X757500Y185200D03*
X789237Y202518D03*
X775000Y202500D03*
X803562Y202483D03*
G54D34*
X126850Y490210D03*
Y487650D03*
Y485090D03*
X120350D03*
Y490210D03*
X320650Y514560D03*
Y512000D03*
Y509440D03*
X314150D03*
Y514560D03*
X369350Y522460D03*
Y519900D03*
Y517340D03*
X362850D03*
Y522460D03*
X364930Y534960D03*
Y532400D03*
Y529840D03*
X358430D03*
Y534960D03*
X382370Y706140D03*
Y708700D03*
Y711260D03*
X388870D03*
Y706140D03*
X354570Y702040D03*
Y704600D03*
Y707160D03*
X361070D03*
Y702040D03*
X354470Y689440D03*
Y692000D03*
Y694560D03*
X360970D03*
Y689440D03*
X573750Y64940D03*
Y67500D03*
X580250Y64940D03*
X573750Y70060D03*
X580250D03*
X551250Y69940D03*
Y72500D03*
Y75060D03*
X557750D03*
Y69940D03*
G54D70*
X629921Y57874D03*
X708661D03*
G54D43*
X141887Y566091D03*
X144037Y555086D03*
X204700Y525000D03*
X195400Y525100D03*
X200055Y524951D03*
X146567Y565991D03*
X151257Y566023D03*
X181505Y581391D03*
X160964Y723068D03*
X214100Y525100D03*
X445900Y37500D03*
X507895Y60397D03*
X496000Y56215D03*
X706580Y321640D03*
G54D16*
X75373Y506479D03*
X75405Y514077D03*
X69878Y506377D03*
X69778Y514077D03*
X64251Y506477D03*
X64151Y514077D03*
X97900Y506600D03*
X92286Y514077D03*
X81032D03*
X97913D03*
X92273Y506600D03*
X81068Y506466D03*
X86673Y506600D03*
X86659Y514077D03*
X136702Y489161D03*
X127800Y614700D03*
X174900Y503100D03*
X191869Y503089D03*
X167000Y517100D03*
X199892Y499622D03*
X162800Y490900D03*
X162700Y517100D03*
X171200Y522400D03*
X159300Y526300D03*
X186111Y516781D03*
X182600Y532600D03*
X145400D03*
X198600Y532800D03*
X186900Y532700D03*
X178600Y532400D03*
X174500D03*
X156501Y560867D03*
X196890Y563900D03*
X200910Y559790D03*
X150067Y610743D03*
X232500Y525800D03*
X266800Y571700D03*
X270947Y573004D03*
X228400Y564350D03*
X238100Y583000D03*
X242000Y590800D03*
X215100Y532600D03*
X242100Y583000D03*
X219200Y533100D03*
X327174Y385918D03*
X310700Y559200D03*
X315290Y678470D03*
X349182Y377874D03*
X345244Y583860D03*
X369500Y572700D03*
X351900Y528900D03*
X380000Y598400D03*
X634000Y190800D03*
X670200Y199900D03*
X730900Y191300D03*
X768529Y195954D03*
X740100Y488084D03*
X735600D03*
X744600D03*
X806100Y222500D03*
X802100D03*
X818100D03*
X814100D03*
X810100D03*
G54D61*
X354800Y612600D03*
X351200D03*
X773200Y262450D03*
X769600D03*
X778390Y247880D03*
X774790D03*
X778550Y251850D03*
X774950D03*
G54D52*
X305906Y182874D03*
G54D17*
X49306Y526995D03*
X41875D03*
X49306Y521269D03*
X41832Y521271D03*
X58500Y575850D03*
X54156Y571795D03*
X49306Y532622D03*
X41865Y532638D03*
X49385Y555153D03*
X41885D03*
X49306Y538249D03*
X41758Y538254D03*
X49306Y543876D03*
X41858Y543881D03*
X49385Y549526D03*
X41903Y549508D03*
X49385Y560879D03*
X41800Y560900D03*
X129170Y499350D03*
X130492Y602854D03*
X167000Y527700D03*
X153115Y464338D03*
Y472738D03*
X197715Y471838D03*
X153015Y476938D03*
X197815Y475938D03*
X175487Y587147D03*
X205440Y624780D03*
X185300Y635300D03*
X163900Y606760D03*
X207100Y641270D03*
X206600Y653100D03*
X200450Y607600D03*
X172902Y629826D03*
X215220Y491100D03*
X242000Y575100D03*
X241900Y558500D03*
X249700Y565900D03*
X241900Y550400D03*
X249717Y569957D03*
X269309Y587813D03*
X241900Y554400D03*
X241700Y562600D03*
Y566700D03*
X242000Y571000D03*
X249732Y579067D03*
X227548Y581666D03*
X243600Y539000D03*
X215200Y634500D03*
X225508Y637894D03*
X214508Y653294D03*
X334700Y512000D03*
X377200Y31000D03*
X374484Y626032D03*
X357000Y683400D03*
X347500Y687500D03*
X370500Y671900D03*
X457400Y33600D03*
X459900Y61900D03*
X441400Y37800D03*
X493194Y34455D03*
X713773Y253883D03*
X712379Y257964D03*
X689000Y265100D03*
X728530Y287930D03*
X689000Y269200D03*
X673400Y307400D03*
X779600Y182200D03*
X793473Y182318D03*
X764700Y180800D03*
X786390Y249880D03*
X807892Y182209D03*
X815628Y253664D03*
X817900Y314600D03*
G54D53*
X336282Y386493D03*
X332407Y393993D03*
X340157D03*
G54D35*
X100130Y576452D03*
X171969Y579940D03*
X201170Y552500D03*
X184120Y611240D03*
X222019Y634188D03*
X215720Y605070D03*
X211700Y638400D03*
X211100Y649500D03*
X321700Y681900D03*
X387800Y700700D03*
X368200Y689500D03*
X609700Y358900D03*
X722850Y256550D03*
X722550Y231460D03*
X722760Y225060D03*
X722700Y262300D03*
X730370Y227400D03*
X730360Y230840D03*
X723140Y249850D03*
X723370Y243700D03*
X722829Y237714D03*
X727350Y284210D03*
X723063Y268702D03*
X732520Y288150D03*
X725100Y275200D03*
X743050Y249900D03*
X771500Y233900D03*
X762300Y262250D03*
X777400Y214700D03*
X738300Y218800D03*
X745800D03*
X777400Y218100D03*
X784919Y218074D03*
X760900Y269000D03*
X746168Y294464D03*
X740060Y287810D03*
X800800Y246800D03*
G54D62*
X466550Y61800D03*
X474050Y65675D03*
Y57925D03*
G54D71*
X638780Y69685D03*
X629921D03*
X621063D03*
X641732Y117323D03*
X638780Y114567D03*
X635827Y120079D03*
X632873Y117323D03*
X629921Y114567D03*
X626969Y120079D03*
X624015Y117323D03*
X621063Y114567D03*
X618110Y120079D03*
X641732Y102362D03*
X638780Y99606D03*
X635827Y105118D03*
X632873Y102362D03*
X629921Y99606D03*
X621063D03*
X624015Y102362D03*
X626969Y105118D03*
X618110D03*
X641732Y87402D03*
X638780Y84646D03*
X635827Y90157D03*
X632873Y87402D03*
X626969Y90157D03*
X629921Y84646D03*
X624015Y87402D03*
X621063Y84646D03*
X618110Y90157D03*
X641732Y72441D03*
X635827Y75197D03*
X632873Y72441D03*
X626969Y75197D03*
X624015Y72441D03*
X618110Y75197D03*
X717520Y69685D03*
X708661D03*
X699803D03*
X720472Y117323D03*
X717520Y114567D03*
X714567Y120079D03*
X711613Y117323D03*
X708661Y114567D03*
X705709Y120079D03*
X702755Y117323D03*
X699803Y114567D03*
X696850Y120079D03*
X720472Y102362D03*
X717520Y99606D03*
X714567Y105118D03*
X711613Y102362D03*
X708661Y99606D03*
X699803D03*
X702755Y102362D03*
X705709Y105118D03*
X696850D03*
X720472Y87402D03*
X717520Y84646D03*
X714567Y90157D03*
X711613Y87402D03*
X705709Y90157D03*
X708661Y84646D03*
X702755Y87402D03*
X699803Y84646D03*
X696850Y90157D03*
X720472Y72441D03*
X714567Y75197D03*
X711613Y72441D03*
X705709Y75197D03*
X702755Y72441D03*
X696850Y75197D03*
G54D44*
X83000Y734600D03*
X838300Y36700D03*
X888800Y696900D03*
G54D80*
X750150Y255200D03*
X752350D03*
X750300Y248900D03*
X752500D03*
X744000Y257400D03*
X746200D03*
X762600Y255200D03*
X764800D03*
X762600Y257400D03*
X764800D03*
X768700Y255150D03*
X770900D03*
X762550Y248900D03*
X764750D03*
X744050Y244850D03*
X746250D03*
X768700Y257350D03*
X770900D03*
X756400Y257400D03*
X758600D03*
X762550Y251100D03*
X764750D03*
X756400Y242600D03*
X758600D03*
X768950Y248940D03*
X771150D03*
X756400Y244800D03*
X758600D03*
X744050Y242600D03*
X746250D03*
X744000Y255200D03*
X746200D03*
X750300Y251100D03*
X752500D03*
X750207Y244805D03*
X752407D03*
X750200Y242600D03*
X752400D03*
X756400Y255200D03*
X758600D03*
X750150Y257400D03*
X752350D03*
X756450Y248900D03*
X758650D03*
X756450Y251100D03*
X758650D03*
X762600Y242600D03*
X764800D03*
X762600Y244800D03*
X764800D03*
X768950Y251140D03*
X771150D03*
X799400Y309500D03*
Y307000D03*
X788000Y269000D03*
X790200D03*
X780410Y276020D03*
X782610D03*
X780100Y279980D03*
X782300D03*
X775890Y284820D03*
X778090D03*
X786293Y285800D03*
X788493D03*
X785390Y266010D03*
X787590D03*
X786020Y283030D03*
X788220D03*
X801600Y309500D03*
Y307000D03*
X803800Y273800D03*
X806000D03*
G54D26*
X54850Y580250D03*
X47468Y567316D03*
X102500Y712200D03*
X196050Y559250D03*
X200059Y577497D03*
X202630Y583440D03*
X190730Y552000D03*
X180060Y615380D03*
X699699Y607558D03*
X763100Y185200D03*
X794837Y202518D03*
X780600Y202500D03*
X809162Y202483D03*
G54D18*
X45906Y526995D03*
X38475D03*
X45906Y521269D03*
X38432Y521271D03*
X55100Y575850D03*
X50756Y571795D03*
X45906Y532622D03*
X38465Y532638D03*
X45985Y555153D03*
X38485D03*
X45906Y538249D03*
X38358Y538254D03*
X45906Y543876D03*
X38458Y543881D03*
X45985Y549526D03*
X38503Y549508D03*
X45985Y560879D03*
X38400Y560900D03*
X125770Y499350D03*
X127092Y602854D03*
X163600Y527700D03*
X149715Y464338D03*
Y472738D03*
X194315Y471838D03*
X149615Y476938D03*
X194415Y475938D03*
X172087Y587147D03*
X202040Y624780D03*
X181900Y635300D03*
X160500Y606760D03*
X203700Y641270D03*
X203200Y653100D03*
X197050Y607600D03*
X169502Y629826D03*
X211820Y491100D03*
X238600Y575100D03*
X238500Y558500D03*
X246300Y565900D03*
X238500Y550400D03*
X246317Y569957D03*
X265909Y587813D03*
X238500Y554400D03*
X238300Y562600D03*
Y566700D03*
X238600Y571000D03*
X246332Y579067D03*
X224148Y581666D03*
X240200Y539000D03*
X211800Y634500D03*
X222108Y637894D03*
X211108Y653294D03*
X331300Y512000D03*
X373800Y31000D03*
X371084Y626032D03*
X353600Y683400D03*
X344100Y687500D03*
X367100Y671900D03*
X454000Y33600D03*
X456500Y61900D03*
X438000Y37800D03*
X489794Y34455D03*
X710373Y253883D03*
X708979Y257964D03*
X685600Y265100D03*
X725130Y287930D03*
X685600Y269200D03*
X670000Y307400D03*
X776200Y182200D03*
X790073Y182318D03*
X761300Y180800D03*
X782990Y249880D03*
X804492Y182209D03*
X812228Y253664D03*
X814500Y314600D03*
G54D81*
X735969Y481247D03*
G54D36*
X103730Y576452D03*
X175569Y579940D03*
X204770Y552500D03*
X187720Y611240D03*
X225619Y634188D03*
X219320Y605070D03*
X215300Y638400D03*
X214700Y649500D03*
X325300Y681900D03*
X391400Y700700D03*
X371800Y689500D03*
X613300Y358900D03*
X726450Y256550D03*
X726150Y231460D03*
X726360Y225060D03*
X726300Y262300D03*
X733970Y227400D03*
X733960Y230840D03*
X726740Y249850D03*
X726970Y243700D03*
X726429Y237714D03*
X730950Y284210D03*
X726663Y268702D03*
X728700Y275200D03*
X746650Y249900D03*
X775100Y233900D03*
X765900Y262250D03*
X781000Y214700D03*
X741900Y218800D03*
X749400D03*
X781000Y218100D03*
X788519Y218074D03*
X764500Y269000D03*
X749768Y294464D03*
X736120Y288150D03*
X743660Y287810D03*
X804400Y246800D03*
G54D45*
X159400Y498300D03*
X165030Y539170D03*
X156391Y590972D03*
X197400Y549000D03*
X153624Y543694D03*
X161750Y535000D03*
X170545Y539779D03*
X175200Y555000D03*
X202380Y567970D03*
X207820Y570860D03*
X206900Y577100D03*
X190500Y547100D03*
X178100Y548700D03*
X155660Y599140D03*
X170200Y603600D03*
X155343Y609168D03*
X158862Y614107D03*
X177750Y603250D03*
X239200Y527000D03*
X220832Y551776D03*
X231892Y546871D03*
X221956Y544587D03*
X223192Y567000D03*
X219688Y587796D03*
X219648Y576801D03*
X219485Y582348D03*
X218801Y571096D03*
X232167Y554962D03*
X219627Y562552D03*
X219691Y557104D03*
X225932Y548276D03*
X359929Y626617D03*
X384365Y605713D03*
X729930Y211940D03*
X723210Y209850D03*
X709650Y249400D03*
X714100Y238800D03*
X711000Y232800D03*
X722961Y300982D03*
X720530Y312210D03*
X733696Y300991D03*
X726800Y313113D03*
X727996Y303699D03*
X711322Y294199D03*
X706997Y283155D03*
X711029Y279114D03*
X713789Y284135D03*
X697960Y292400D03*
X703526Y275939D03*
X714519Y275114D03*
X707604Y272070D03*
X698773Y278597D03*
X709600Y299400D03*
X718600Y304300D03*
X715200Y300000D03*
X709500Y308400D03*
X693200Y279550D03*
X702109Y297903D03*
X702400Y286700D03*
X700700Y305100D03*
X716060Y309320D03*
X706600Y303800D03*
X691774Y288967D03*
X714400Y268600D03*
X718260Y294951D03*
X744960Y197430D03*
X797500Y226000D03*
X791140Y247740D03*
X753479Y207914D03*
X752700Y214100D03*
X744768Y300864D03*
X748100Y281300D03*
X748000Y288000D03*
X741100Y307400D03*
X739100Y302126D03*
X736952Y311391D03*
X743800Y278600D03*
X736800Y278300D03*
X815670Y242890D03*
X820100Y252600D03*
X802000Y232500D03*
X823100Y225400D03*
X811000Y234300D03*
X816400Y235900D03*
X807000Y230500D03*
X812630Y249229D03*
X828781Y231061D03*
X806400Y257300D03*
G54D72*
X651575Y20039D03*
X608267D03*
X641732Y126811D03*
X624015D03*
X651575Y72441D03*
X608267D03*
X730315Y20039D03*
X687007D03*
X720472Y126811D03*
X702755D03*
X730315Y72441D03*
X687007D03*
G54D54*
X305906Y388386D03*
G54D27*
X74400Y556700D03*
X102700Y507100D03*
X141107Y484000D03*
X132899Y489111D03*
X101800Y493000D03*
X126950Y495528D03*
X108492Y541947D03*
X138350Y584250D03*
X130400Y539899D03*
X126780Y562772D03*
X117121Y579998D03*
X123500Y613100D03*
X141971Y624700D03*
X105600Y597000D03*
X105400Y601300D03*
X104600Y609900D03*
X105600Y605900D03*
X104600Y614000D03*
X104500Y618800D03*
X116200Y611600D03*
X116023Y607423D03*
X119400Y614100D03*
X116400Y616900D03*
X134700Y604000D03*
X129903Y634500D03*
X118998Y701124D03*
X115598Y708228D03*
X109478Y713245D03*
X176000Y460200D03*
X171492Y496413D03*
X190416Y498361D03*
X183300Y493100D03*
X202190Y471014D03*
X202271Y475938D03*
X205447Y487762D03*
X162530Y500950D03*
X182874Y523590D03*
X165900Y524100D03*
X171571Y487041D03*
X176800Y495900D03*
X175700Y521000D03*
X199881Y507507D03*
X188065Y523962D03*
X203065Y493980D03*
X196200Y482600D03*
X158000Y476938D03*
X157800Y471800D03*
X158200Y467100D03*
X189500Y471900D03*
X190200Y476000D03*
X154660Y510100D03*
X195900Y503600D03*
X195379Y510158D03*
X153938Y526490D03*
X190603Y519531D03*
X152332Y583318D03*
X191100Y539700D03*
X180540Y539941D03*
X187600Y542450D03*
X203900Y542626D03*
X145150Y540250D03*
X175545Y539699D03*
X165085Y532153D03*
X169200Y534900D03*
X159327Y539484D03*
X152170Y593440D03*
X156501Y567965D03*
X194942Y536499D03*
X199700Y541100D03*
X206700Y539600D03*
X149093Y541418D03*
X197198Y595513D03*
X194490Y645390D03*
X196500Y603912D03*
X197300Y616100D03*
X198086Y624715D03*
X177378Y637409D03*
X150790Y598540D03*
X151550Y629800D03*
X163300Y602600D03*
X156669Y604185D03*
X153720Y614010D03*
X207569Y629750D03*
X201000Y603600D03*
X145710Y596640D03*
X185246Y603254D03*
X148000Y606650D03*
X184300Y594500D03*
X146800Y629900D03*
X204150Y645180D03*
X199600Y650100D03*
X192960Y628510D03*
X187900Y628500D03*
X162098Y697235D03*
X150849Y710215D03*
X155846Y723282D03*
X228700Y450600D03*
X238500Y448250D03*
X254500Y509600D03*
X222508Y479092D03*
X241947Y514306D03*
X228700Y490717D03*
X230700Y486658D03*
X249640Y495080D03*
X234700Y490900D03*
X219800Y490550D03*
X268448Y520801D03*
X233400Y560600D03*
X233100Y569900D03*
X262911Y568331D03*
X262603Y564342D03*
X233400Y579300D03*
X234722Y574814D03*
X224359Y562475D03*
X225530Y537192D03*
X253700Y531240D03*
X254905Y555761D03*
X232536Y588078D03*
X235700Y593300D03*
X237775Y545900D03*
X212000Y539600D03*
X265700Y580209D03*
X247000Y574567D03*
X253400Y571400D03*
X231000Y536584D03*
X238000Y532500D03*
X235772Y542321D03*
X212000Y608700D03*
X216000Y626900D03*
X218000Y630400D03*
X249700Y613590D03*
X213161Y623100D03*
X240900Y635200D03*
X227900Y606900D03*
X218968Y600635D03*
X215519Y594866D03*
X231066Y602763D03*
X253583Y653829D03*
X233100Y623400D03*
X256788Y697212D03*
X249090Y676611D03*
X259000Y672225D03*
X334200Y241900D03*
X312300Y247900D03*
X325147Y252424D03*
X313077Y257074D03*
X311464Y381211D03*
X339900Y454200D03*
X332816Y425682D03*
X339269Y407733D03*
X302175Y521026D03*
X286797Y516522D03*
X314370Y520789D03*
X292100Y516000D03*
X297400Y517981D03*
X327600Y515900D03*
X278400Y463300D03*
X333800Y534830D03*
X329840Y572710D03*
X301653Y572452D03*
X325475Y572818D03*
X322858Y560820D03*
X288700Y586900D03*
X322794Y568615D03*
X285564Y582990D03*
X298000Y561000D03*
X328580Y568120D03*
X320954Y572631D03*
X315500Y563050D03*
Y568700D03*
X340538Y563970D03*
X338200Y558000D03*
X337346Y545100D03*
X322423Y549010D03*
X315600Y557700D03*
X308200Y593153D03*
X325300Y648700D03*
X330400Y644300D03*
X327300Y655300D03*
X323191Y618260D03*
X333600Y628023D03*
X327250Y701500D03*
X333338Y696953D03*
X319950Y662500D03*
X303900Y661300D03*
X314250Y662600D03*
X303800Y681682D03*
X360600Y22300D03*
X365900Y67100D03*
X385673Y424903D03*
X389151Y436223D03*
X364577Y425023D03*
X390229Y508189D03*
X352111Y517737D03*
X373383Y511449D03*
X373800Y503000D03*
X378267Y496100D03*
X360300Y590390D03*
X344066Y579700D03*
X358100Y572200D03*
X344163Y553395D03*
X356300Y549100D03*
X364964Y588771D03*
X360500Y566200D03*
X377635Y616107D03*
X378800Y624850D03*
X342600Y682800D03*
X388017Y660594D03*
X362900Y683800D03*
X349190Y682490D03*
X377199Y699873D03*
X347010Y692076D03*
X341500Y707000D03*
X380387Y685261D03*
X392500Y673500D03*
X362700Y671900D03*
X458500Y27000D03*
X443500Y42000D03*
X439288Y46921D03*
X459700Y66000D03*
X436154Y72470D03*
X508100Y50100D03*
X495500Y61115D03*
X502930Y64170D03*
X489691Y42317D03*
X481093Y67669D03*
X494800Y74100D03*
X544814Y62686D03*
X564500Y64100D03*
X586155Y393023D03*
X627930Y198500D03*
X657603Y294530D03*
X652465Y294735D03*
X626988Y367660D03*
X604000Y501806D03*
X627408Y553791D03*
X640400Y557600D03*
X648800Y546000D03*
X715775Y261939D03*
X714226Y249665D03*
X695697Y269200D03*
X701654Y267100D03*
X693277Y313344D03*
X686714Y298448D03*
X695200Y301800D03*
X720900Y434172D03*
X734300Y496000D03*
X716442Y560260D03*
X699472Y560300D03*
X694000Y603000D03*
X711256Y595499D03*
X699899Y602970D03*
X768700Y180900D03*
X768579Y203964D03*
X787770Y254660D03*
X798770Y259500D03*
X796222Y208966D03*
X784200Y207100D03*
X744482Y202110D03*
X735300Y401957D03*
X755100Y486700D03*
X739300Y496000D03*
X755100Y481900D03*
X754883Y498500D03*
X810500Y262400D03*
X813491Y206953D03*
X820625Y345848D03*
X801880Y355479D03*
X817800Y479600D03*
X804100Y479200D03*
G54D63*
X421653Y126378D03*
X435827D03*
X450000D03*
X464173D03*
X428740Y121654D03*
X442913D03*
X457086D03*
X471260D03*
X421653Y130709D03*
X428740Y125985D03*
X435827Y130709D03*
X442913Y125985D03*
X450000Y130709D03*
X457086Y125985D03*
X464173Y130709D03*
X471260Y125985D03*
X428740Y131496D03*
X442913D03*
X457086D03*
X471260D03*
X421653Y183071D03*
X435827D03*
X450000D03*
X464173D03*
X421653Y136221D03*
X435827D03*
X450000D03*
X464173D03*
X421653Y140551D03*
X428740Y135827D03*
X435827Y140551D03*
X442913Y135827D03*
X450000Y140551D03*
X457086Y135827D03*
X464173Y140551D03*
X471260Y135827D03*
X421653Y144882D03*
X428740Y140158D03*
X435827Y144882D03*
X442913Y140158D03*
X450000Y144882D03*
X457086Y140158D03*
X464173Y144882D03*
X471260Y140158D03*
X421653Y150394D03*
X428740Y145670D03*
X435827Y150394D03*
X442913Y145670D03*
X450000Y150394D03*
X457086Y145670D03*
X464173Y150394D03*
X471260Y145670D03*
X421653Y154725D03*
X428740Y150000D03*
X435827Y154725D03*
X442913Y150000D03*
X450000Y154725D03*
X457086Y150000D03*
X464173Y154725D03*
X471260Y150000D03*
X421653Y159055D03*
X428740Y154331D03*
X435827Y159055D03*
X442913Y154331D03*
X450000Y159055D03*
X457086Y154331D03*
X464173Y159055D03*
X471260Y154331D03*
X421653Y164567D03*
X428740Y159843D03*
X435827Y164567D03*
X442913Y159843D03*
X450000Y164567D03*
X457086Y159843D03*
X464173Y164567D03*
X471260Y159843D03*
X421653Y168898D03*
X428740Y164173D03*
X435827Y168898D03*
X442913Y164173D03*
X450000Y168898D03*
X457086Y164173D03*
X464173Y168898D03*
X471260Y164173D03*
X421653Y173229D03*
X428740Y168504D03*
X435827Y173229D03*
X442913Y168504D03*
X450000Y173229D03*
X457086Y168504D03*
X464173Y173229D03*
X471260Y168504D03*
X421653Y178740D03*
X428740Y174016D03*
X435827Y178740D03*
X442913Y174016D03*
X450000Y178740D03*
X457086Y174016D03*
X464173Y178740D03*
X471260Y174016D03*
X506693Y126378D03*
X520866D03*
X535039D03*
X513779Y121654D03*
X527953D03*
X506693Y130709D03*
X513779Y125985D03*
X520866Y130709D03*
X527953Y125985D03*
X535039Y130709D03*
X513779Y131496D03*
X527953D03*
X506693Y183071D03*
X520866D03*
X535039D03*
X506693Y136221D03*
X520866D03*
X535039D03*
X506693Y140551D03*
X513779Y135827D03*
X520866Y140551D03*
X527953Y135827D03*
X535039Y140551D03*
X506693Y144882D03*
X513779Y140158D03*
X520866Y144882D03*
X527953Y140158D03*
X535039Y144882D03*
X506693Y150394D03*
X513779Y145670D03*
X520866Y150394D03*
X527953Y145670D03*
X535039Y150394D03*
X506693Y154725D03*
X513779Y150000D03*
X520866Y154725D03*
X527953Y150000D03*
X535039Y154725D03*
X506693Y159055D03*
X513779Y154331D03*
X520866Y159055D03*
X527953Y154331D03*
X535039Y159055D03*
X506693Y164567D03*
X513779Y159843D03*
X520866Y164567D03*
X527953Y159843D03*
X535039Y164567D03*
X506693Y168898D03*
X513779Y164173D03*
X520866Y168898D03*
X527953Y164173D03*
X535039Y168898D03*
X506693Y173229D03*
X513779Y168504D03*
X520866Y173229D03*
X527953Y168504D03*
X535039Y173229D03*
X506693Y178740D03*
X513779Y174016D03*
X520866Y178740D03*
X527953Y174016D03*
X535039Y178740D03*
X549212Y126378D03*
X542126Y121654D03*
X556299D03*
X542126Y125985D03*
X549212Y130709D03*
X556299Y125985D03*
X542126Y131496D03*
X556299D03*
X549212Y183071D03*
Y136221D03*
X542126Y135827D03*
X549212Y140551D03*
X556299Y135827D03*
X542126Y140158D03*
X549212Y144882D03*
X556299Y140158D03*
X542126Y145670D03*
X549212Y150394D03*
X556299Y145670D03*
X542126Y150000D03*
X549212Y154725D03*
X556299Y150000D03*
X542126Y154331D03*
X549212Y159055D03*
X556299Y154331D03*
X542126Y159843D03*
X549212Y164567D03*
X556299Y159843D03*
X542126Y164173D03*
X549212Y168898D03*
X556299Y164173D03*
X542126Y168504D03*
X549212Y173229D03*
X556299Y168504D03*
X542126Y174016D03*
X549212Y178740D03*
X556299Y174016D03*
G54D82*
G01X13215Y-125739D02*
X14089Y-124864D01*
X14744Y-123406D01*
X15181Y-121363D01*
X14744Y-119614D01*
X13871Y-118447D01*
X12342Y-117572D01*
X6447D01*
Y-135072D01*
X13652D01*
X15181Y-133906D01*
X16054Y-132155D01*
X16491Y-130114D01*
X16054Y-128072D01*
X14744Y-126322D01*
X13215Y-125739D01*
X6447D01*
G01X25912Y-135072D02*
Y-123406D01*
G01Y-125739D02*
X27004Y-124572D01*
X28096Y-123697D01*
X29624Y-123406D01*
X30715Y-123697D01*
X32026Y-124572D01*
G01X41884Y-140322D02*
X43194Y-140905D01*
X44941Y-140322D01*
X46032Y-139156D01*
X46906Y-137697D01*
X48215Y-133031D01*
X51054Y-123406D01*
G01X44067D02*
X48215Y-133031D01*
G01X67462Y-124864D02*
X65934Y-123697D01*
X64624Y-123406D01*
X62877Y-123989D01*
X61567Y-125155D01*
X60694Y-127197D01*
X60475Y-129239D01*
X60694Y-131281D01*
X61567Y-133031D01*
X62877Y-134489D01*
X64624Y-135072D01*
X66152Y-134489D01*
X67462Y-133322D01*
G01X78194Y-127197D02*
X85181D01*
X84526Y-125155D01*
X83434Y-123989D01*
X81906Y-123406D01*
X80377Y-123697D01*
X79067Y-124572D01*
X78194Y-126614D01*
X77757Y-128364D01*
Y-130114D01*
X78194Y-131864D01*
X79286Y-133614D01*
X80596Y-134780D01*
X82124Y-135072D01*
X83652Y-134489D01*
X85181Y-132739D01*
G01X121272Y-119031D02*
X119962Y-118155D01*
X118434Y-117572D01*
X116687D01*
X114722Y-118447D01*
X113194Y-119905D01*
X112102Y-121656D01*
X111229Y-124572D01*
X111010Y-127197D01*
X111447Y-129822D01*
X112102Y-131572D01*
X113412Y-133322D01*
X114941Y-134489D01*
X116469Y-135072D01*
X117997D01*
X119526Y-134489D01*
X120836Y-133614D01*
X121928Y-132448D01*
G01X137899Y-135072D02*
Y-123406D01*
G01Y-125447D02*
X137026Y-124281D01*
X135715Y-123697D01*
X134187Y-123406D01*
X132659Y-123989D01*
X131349Y-125155D01*
X130475Y-126905D01*
X130039Y-129239D01*
X130475Y-131572D01*
X131349Y-133322D01*
X132659Y-134489D01*
X134187Y-135072D01*
X135715Y-134780D01*
X137026Y-133906D01*
X137899Y-132739D01*
G01X147757Y-135072D02*
Y-123406D01*
G01Y-126322D02*
X148631Y-124864D01*
X149941Y-123697D01*
X151687Y-123406D01*
X153215Y-123697D01*
X154526Y-124864D01*
X155181Y-126905D01*
Y-135072D01*
G01X164384Y-140322D02*
X165694Y-140905D01*
X167441Y-140322D01*
X168532Y-139156D01*
X169406Y-137697D01*
X170715Y-133031D01*
X173554Y-123406D01*
G01X166567D02*
X170715Y-133031D01*
G01X186469Y-135072D02*
X185159Y-134780D01*
X183849Y-133614D01*
X182975Y-131572D01*
X182539Y-129239D01*
X182975Y-126905D01*
X183849Y-124864D01*
X185159Y-123697D01*
X186469Y-123406D01*
X187779Y-123697D01*
X189089Y-124864D01*
X189962Y-126905D01*
X190181Y-129239D01*
X189962Y-131572D01*
X189089Y-133614D01*
X187779Y-134780D01*
X186469Y-135072D01*
G01X200257D02*
Y-123406D01*
G01Y-126322D02*
X201131Y-124864D01*
X202441Y-123697D01*
X204187Y-123406D01*
X205715Y-123697D01*
X207026Y-124864D01*
X207681Y-126905D01*
Y-135072D01*
G01X236349Y-117572D02*
X241589D01*
G01X238969D02*
Y-135072D01*
G01X236349D02*
X241589D01*
G01X256469D02*
X254722Y-134780D01*
X253194Y-133614D01*
X251884Y-131864D01*
X251010Y-129822D01*
X250574Y-127489D01*
Y-125155D01*
X251010Y-122822D01*
X251884Y-120780D01*
X253194Y-119031D01*
X254722Y-117864D01*
X256469Y-117572D01*
X258215Y-117864D01*
X259744Y-119031D01*
X261054Y-120780D01*
X261928Y-122822D01*
X262364Y-125155D01*
Y-127489D01*
X261928Y-129822D01*
X261054Y-131864D01*
X259744Y-133614D01*
X258215Y-134780D01*
X256469Y-135072D01*
G01X268292D02*
Y-117572D01*
X273969Y-132155D01*
X279646Y-117572D01*
Y-135072D01*
G01X307877Y-140905D02*
X305694Y-137989D01*
X304602Y-135072D01*
Y-123406D01*
X305694Y-120489D01*
X307877Y-117572D01*
G01X321010Y-123406D02*
X323631Y-135072D01*
X326469Y-123406D01*
X329307Y-135072D01*
X331928Y-123406D01*
G01X340039Y-135655D02*
X347899Y-117572D01*
G01X376349D02*
X381589D01*
G01X378969D02*
Y-135072D01*
G01X376349D02*
X381589D01*
G01X396469D02*
X394722Y-134780D01*
X393194Y-133614D01*
X391884Y-131864D01*
X391010Y-129822D01*
X390574Y-127489D01*
Y-125155D01*
X391010Y-122822D01*
X391884Y-120780D01*
X393194Y-119031D01*
X394722Y-117864D01*
X396469Y-117572D01*
X398215Y-117864D01*
X399744Y-119031D01*
X401054Y-120780D01*
X401928Y-122822D01*
X402364Y-125155D01*
Y-127489D01*
X401928Y-129822D01*
X401054Y-131864D01*
X399744Y-133614D01*
X398215Y-134780D01*
X396469Y-135072D01*
G01X418772Y-119031D02*
X417462Y-118155D01*
X415934Y-117572D01*
X414187D01*
X412222Y-118447D01*
X410694Y-119905D01*
X409602Y-121656D01*
X408729Y-124572D01*
X408510Y-127197D01*
X408947Y-129822D01*
X409602Y-131572D01*
X410912Y-133322D01*
X412441Y-134489D01*
X413969Y-135072D01*
X415497D01*
X417026Y-134489D01*
X418336Y-133614D01*
X419428Y-132448D01*
G01X432561Y-140905D02*
X434744Y-137989D01*
X435836Y-135072D01*
Y-123406D01*
X434744Y-120489D01*
X432561Y-117572D01*
G01X180792Y-90072D02*
Y-72572D01*
X186469Y-87155D01*
X192146Y-72572D01*
Y-90072D01*
G01X203969D02*
X202659Y-89780D01*
X201349Y-88614D01*
X200475Y-86572D01*
X200039Y-84239D01*
X200475Y-81905D01*
X201349Y-79864D01*
X202659Y-78697D01*
X203969Y-78406D01*
X205279Y-78697D01*
X206589Y-79864D01*
X207462Y-81905D01*
X207681Y-84239D01*
X207462Y-86572D01*
X206589Y-88614D01*
X205279Y-89780D01*
X203969Y-90072D01*
G01X225399Y-72572D02*
Y-90072D01*
G01Y-87448D02*
X224526Y-88906D01*
X223215Y-89780D01*
X221687Y-90072D01*
X219941Y-89489D01*
X218631Y-88031D01*
X217757Y-86281D01*
X217539Y-84239D01*
X217757Y-82197D01*
X218631Y-80447D01*
X219941Y-78989D01*
X221687Y-78406D01*
X223215Y-78697D01*
X224307Y-79281D01*
X225399Y-80447D01*
G01X235694Y-82197D02*
X242681D01*
X242026Y-80155D01*
X240934Y-78989D01*
X239406Y-78406D01*
X237877Y-78697D01*
X236567Y-79572D01*
X235694Y-81614D01*
X235257Y-83364D01*
Y-85114D01*
X235694Y-86864D01*
X236786Y-88614D01*
X238096Y-89780D01*
X239624Y-90072D01*
X241152Y-89489D01*
X242681Y-87739D01*
G01X256469Y-90072D02*
Y-72572D01*
G01X490269Y-135072D02*
Y-117572D01*
X487649Y-121072D01*
G01Y-135072D02*
X492889D01*
G01X503621Y-127781D02*
X505149Y-125739D01*
X506459Y-124572D01*
X508206Y-123989D01*
X509734Y-124572D01*
X510826Y-125739D01*
X511699Y-127489D01*
X511917Y-129530D01*
X511699Y-131281D01*
X510826Y-133031D01*
X509515Y-134489D01*
X507987Y-135072D01*
X506241Y-134489D01*
X504712Y-132739D01*
X503839Y-130114D01*
X503621Y-127197D01*
X504057Y-123406D01*
X504712Y-121363D01*
X505804Y-119322D01*
X507332Y-117864D01*
X508861Y-117572D01*
X510389Y-118155D01*
X511481Y-119614D01*
G01X520466Y-131572D02*
X521775Y-133614D01*
X523522Y-134780D01*
X525487Y-135072D01*
X527234Y-134780D01*
X528981Y-133322D01*
X530072Y-131572D01*
X530291Y-129822D01*
X529854Y-127781D01*
X528326Y-126322D01*
X526797Y-125739D01*
X524832D01*
G01X526797D02*
X528107Y-124864D01*
X529199Y-123406D01*
X529636Y-121656D01*
X529199Y-119905D01*
X528107Y-118447D01*
X526142Y-117572D01*
X524177Y-117864D01*
X522212Y-119031D01*
G01X542769Y-135072D02*
Y-117572D01*
X540149Y-121072D01*
G01Y-135072D02*
X545389D01*
G01X560269D02*
X561797Y-134780D01*
X563544Y-133906D01*
X564636Y-132448D01*
X565072Y-130405D01*
X564636Y-128364D01*
X563326Y-126614D01*
X561361Y-125739D01*
X559177D01*
X557867Y-125155D01*
X556775Y-123697D01*
X556339Y-121656D01*
X556994Y-119614D01*
X558522Y-118155D01*
X560269Y-117572D01*
X562015Y-118155D01*
X563544Y-119614D01*
X564199Y-121656D01*
X563762Y-123697D01*
X562671Y-125155D01*
X561361Y-125739D01*
X559177D01*
X557212Y-126614D01*
X555902Y-128364D01*
X555466Y-130405D01*
X555902Y-132448D01*
X556994Y-133906D01*
X558741Y-134780D01*
X560269Y-135072D01*
G01X477152Y-90072D02*
Y-72572D01*
X482392D01*
X484139Y-73447D01*
X485449Y-75489D01*
X485886Y-77822D01*
X485449Y-80155D01*
X484357Y-81905D01*
X482392Y-82781D01*
X477152D01*
G01X503822Y-74031D02*
X502512Y-73155D01*
X500984Y-72572D01*
X499237D01*
X497272Y-73447D01*
X495744Y-74905D01*
X494652Y-76656D01*
X493779Y-79572D01*
X493560Y-82197D01*
X493997Y-84822D01*
X494652Y-86572D01*
X495962Y-88322D01*
X497491Y-89489D01*
X499019Y-90072D01*
X500547D01*
X502076Y-89489D01*
X503386Y-88614D01*
X504478Y-87448D01*
G01X518265Y-80739D02*
X519139Y-79864D01*
X519794Y-78406D01*
X520231Y-76363D01*
X519794Y-74614D01*
X518921Y-73447D01*
X517392Y-72572D01*
X511497D01*
Y-90072D01*
X518702D01*
X520231Y-88906D01*
X521104Y-87155D01*
X521541Y-85114D01*
X521104Y-83072D01*
X519794Y-81322D01*
X518265Y-80739D01*
X511497D01*
G01X527469Y-95905D02*
X540569D01*
G01X546497Y-90072D02*
Y-72572D01*
X556541Y-90072D01*
Y-72572D01*
G01X569019Y-90072D02*
X567272Y-89780D01*
X565744Y-88614D01*
X564434Y-86864D01*
X563560Y-84822D01*
X563124Y-82489D01*
Y-80155D01*
X563560Y-77822D01*
X564434Y-75780D01*
X565744Y-74031D01*
X567272Y-72864D01*
X569019Y-72572D01*
X570765Y-72864D01*
X572294Y-74031D01*
X573604Y-75780D01*
X574478Y-77822D01*
X574914Y-80155D01*
Y-82489D01*
X574478Y-84822D01*
X573604Y-86864D01*
X572294Y-88614D01*
X570765Y-89780D01*
X569019Y-90072D01*
G01X647421Y-120489D02*
X648731Y-118739D01*
X650259Y-117864D01*
X652006Y-117572D01*
X654189Y-118155D01*
X655717Y-119614D01*
X656154Y-121363D01*
X655936Y-123114D01*
X655062Y-124572D01*
X650696Y-127489D01*
X648731Y-129530D01*
X647421Y-132448D01*
X646984Y-135072D01*
X656154D01*
G01X619860Y-72572D02*
X625319Y-90072D01*
X630778Y-72572D01*
G01X647186Y-90072D02*
X638452D01*
Y-72572D01*
X647186D01*
G01X643692Y-81030D02*
X638452D01*
G01X655952Y-90072D02*
Y-72572D01*
X661411D01*
X663157Y-73447D01*
X664249Y-74614D01*
X664686Y-76947D01*
X664249Y-79281D01*
X662939Y-80739D01*
X661411Y-81614D01*
X655952D01*
G01X661411D02*
X664686Y-90072D01*
G01X677819Y-90655D02*
X677382Y-90364D01*
Y-89780D01*
X677819Y-89489D01*
X678256Y-89780D01*
Y-90364D01*
X677819Y-90655D01*
G01X826023Y-125739D02*
X825149Y-124864D01*
X824494Y-123406D01*
X824057Y-121363D01*
X824494Y-119614D01*
X825367Y-118447D01*
X826896Y-117572D01*
X832791D01*
Y-135072D01*
X825586D01*
X824057Y-133906D01*
X823184Y-132155D01*
X822747Y-130114D01*
X823184Y-128072D01*
X824494Y-126322D01*
X826023Y-125739D01*
X832791D01*
G01X815946Y-135072D02*
Y-117572D01*
X810269Y-132155D01*
X804592Y-117572D01*
Y-135072D01*
G01X798228D02*
X792769Y-117572D01*
X787310Y-135072D01*
G01X789276Y-128947D02*
X796263D01*
G01X779854Y-132739D02*
X778107Y-134197D01*
X776142Y-135072D01*
X774396D01*
X772649Y-134197D01*
X771339Y-132739D01*
X770684Y-130697D01*
X771121Y-128656D01*
X772212Y-126905D01*
X774177Y-125739D01*
X776797Y-125155D01*
X778326Y-123989D01*
X778981Y-121947D01*
X778544Y-119905D01*
X777452Y-118447D01*
X775924Y-117572D01*
X774396D01*
X772867Y-118155D01*
X771557Y-119614D01*
G01X762572Y-135072D02*
Y-117572D01*
G01X754276D02*
X762572Y-128364D01*
G01X752966Y-135072D02*
X758861Y-123406D01*
G01X753402Y-72572D02*
Y-90072D01*
X762136D01*
G01X779199D02*
Y-78406D01*
G01Y-80447D02*
X778326Y-79281D01*
X777015Y-78697D01*
X775487Y-78406D01*
X773959Y-78989D01*
X772649Y-80155D01*
X771775Y-81905D01*
X771339Y-84239D01*
X771775Y-86572D01*
X772649Y-88322D01*
X773959Y-89489D01*
X775487Y-90072D01*
X777015Y-89780D01*
X778326Y-88906D01*
X779199Y-87739D01*
G01X788184Y-95322D02*
X789494Y-95905D01*
X791241Y-95322D01*
X792332Y-94156D01*
X793206Y-92697D01*
X794515Y-88031D01*
X797354Y-78406D01*
G01X790367D02*
X794515Y-88031D01*
G01X806994Y-82197D02*
X813981D01*
X813326Y-80155D01*
X812234Y-78989D01*
X810706Y-78406D01*
X809177Y-78697D01*
X807867Y-79572D01*
X806994Y-81614D01*
X806557Y-83364D01*
Y-85114D01*
X806994Y-86864D01*
X808086Y-88614D01*
X809396Y-89780D01*
X810924Y-90072D01*
X812452Y-89489D01*
X813981Y-87739D01*
G01X824712Y-90072D02*
Y-78406D01*
G01Y-80739D02*
X825804Y-79572D01*
X826896Y-78697D01*
X828424Y-78406D01*
X829515Y-78697D01*
X830826Y-79572D01*
G01X917819Y-135072D02*
X916072Y-134780D01*
X914544Y-133614D01*
X913234Y-131864D01*
X912360Y-129822D01*
X911924Y-127489D01*
Y-125155D01*
X912360Y-122822D01*
X913234Y-120780D01*
X914544Y-119031D01*
X916072Y-117864D01*
X917819Y-117572D01*
X919565Y-117864D01*
X921094Y-119031D01*
X922404Y-120780D01*
X923278Y-122822D01*
X923714Y-125155D01*
Y-127489D01*
X923278Y-129822D01*
X922404Y-131864D01*
X921094Y-133614D01*
X919565Y-134780D01*
X917819Y-135072D01*
G01X919565Y-130405D02*
X922186Y-135072D01*
G01X930516Y-117572D02*
Y-130114D01*
X931389Y-132739D01*
X933136Y-134489D01*
X935319Y-135072D01*
X937502Y-134489D01*
X939249Y-132739D01*
X940122Y-130114D01*
Y-117572D01*
G01X950199D02*
X955439D01*
G01X952819D02*
Y-135072D01*
G01X950199D02*
X955439D01*
G01X965297D02*
Y-117572D01*
X975341Y-135072D01*
Y-117572D01*
G01X992622Y-119031D02*
X991312Y-118155D01*
X989784Y-117572D01*
X988037D01*
X986072Y-118447D01*
X984544Y-119905D01*
X983452Y-121656D01*
X982579Y-124572D01*
X982360Y-127197D01*
X982797Y-129822D01*
X983452Y-131572D01*
X984762Y-133322D01*
X986291Y-134489D01*
X987819Y-135072D01*
X989347D01*
X990876Y-134489D01*
X992186Y-133614D01*
X993278Y-132448D01*
G01X1005319Y-135072D02*
Y-127197D01*
X1000952Y-117572D01*
G01X1009686D02*
X1005319Y-127197D01*
G01X895516Y-90072D02*
Y-72572D01*
X899882D01*
X901629Y-73447D01*
X902939Y-74614D01*
X904031Y-76363D01*
X904904Y-78406D01*
X905122Y-81322D01*
X904904Y-84239D01*
X904031Y-86281D01*
X902939Y-88031D01*
X901629Y-89197D01*
X899882Y-90072D01*
X895516D01*
G01X914544Y-82197D02*
X921531D01*
X920876Y-80155D01*
X919784Y-78989D01*
X918256Y-78406D01*
X916727Y-78697D01*
X915417Y-79572D01*
X914544Y-81614D01*
X914107Y-83364D01*
Y-85114D01*
X914544Y-86864D01*
X915636Y-88614D01*
X916946Y-89780D01*
X918474Y-90072D01*
X920002Y-89489D01*
X921531Y-87739D01*
G01X932044Y-88031D02*
X933136Y-89197D01*
X934664Y-90072D01*
X935974D01*
X937284Y-89489D01*
X938157Y-88614D01*
X938594Y-87448D01*
X938376Y-85697D01*
X937502Y-84822D01*
X933572Y-83072D01*
X932699Y-81030D01*
X933136Y-79572D01*
X934009Y-78697D01*
X935319Y-78406D01*
X936629Y-78697D01*
X937939Y-79572D01*
G01X952819Y-78406D02*
Y-90072D01*
G01Y-73739D02*
X952382Y-73447D01*
Y-72864D01*
X952819Y-72572D01*
X953256Y-72864D01*
Y-73447D01*
X952819Y-73739D01*
G01X967262Y-94447D02*
X968791Y-95614D01*
X970537Y-95905D01*
X972065Y-95614D01*
X973376Y-94156D01*
X974249Y-92114D01*
Y-78406D01*
G01Y-80739D02*
X973376Y-79572D01*
X972065Y-78697D01*
X970537Y-78406D01*
X968791Y-78989D01*
X967699Y-80155D01*
X966825Y-82197D01*
X966389Y-84239D01*
X966607Y-85989D01*
X967481Y-88031D01*
X968791Y-89489D01*
X970537Y-90072D01*
X971847Y-89780D01*
X973376Y-88614D01*
X974249Y-87448D01*
G01X984107Y-90072D02*
Y-78406D01*
G01Y-81322D02*
X984981Y-79864D01*
X986291Y-78697D01*
X988037Y-78406D01*
X989565Y-78697D01*
X990876Y-79864D01*
X991531Y-81905D01*
Y-90072D01*
G01X1002044Y-82197D02*
X1009031D01*
X1008376Y-80155D01*
X1007284Y-78989D01*
X1005756Y-78406D01*
X1004227Y-78697D01*
X1002917Y-79572D01*
X1002044Y-81614D01*
X1001607Y-83364D01*
Y-85114D01*
X1002044Y-86864D01*
X1003136Y-88614D01*
X1004446Y-89780D01*
X1005974Y-90072D01*
X1007502Y-89489D01*
X1009031Y-87739D01*
G01X1019762Y-90072D02*
Y-78406D01*
G01Y-80739D02*
X1020854Y-79572D01*
X1021946Y-78697D01*
X1023474Y-78406D01*
X1024565Y-78697D01*
X1025876Y-79572D01*
G01X1066519Y-117572D02*
X1064772Y-118155D01*
X1063462Y-119614D01*
X1062589Y-121363D01*
X1061934Y-123697D01*
X1061716Y-126322D01*
X1061934Y-128947D01*
X1062589Y-131281D01*
X1063462Y-133031D01*
X1064772Y-134489D01*
X1066519Y-135072D01*
X1068265Y-134489D01*
X1069576Y-133031D01*
X1070449Y-131281D01*
X1071104Y-128947D01*
X1071322Y-126322D01*
X1071104Y-123697D01*
X1070449Y-121363D01*
X1069576Y-119614D01*
X1068265Y-118155D01*
X1066519Y-117572D01*
G01X1084019Y-135072D02*
X1085547Y-134780D01*
X1087294Y-133906D01*
X1088386Y-132448D01*
X1088822Y-130405D01*
X1088386Y-128364D01*
X1087076Y-126614D01*
X1085111Y-125739D01*
X1082927D01*
X1081617Y-125155D01*
X1080525Y-123697D01*
X1080089Y-121656D01*
X1080744Y-119614D01*
X1082272Y-118155D01*
X1084019Y-117572D01*
X1085765Y-118155D01*
X1087294Y-119614D01*
X1087949Y-121656D01*
X1087512Y-123697D01*
X1086421Y-125155D01*
X1085111Y-125739D01*
X1082927D01*
X1080962Y-126614D01*
X1079652Y-128364D01*
X1079216Y-130405D01*
X1079652Y-132448D01*
X1080744Y-133906D01*
X1082491Y-134780D01*
X1084019Y-135072D01*
G01X1097589Y-135655D02*
X1105449Y-117572D01*
G01X1119019D02*
X1117272Y-118155D01*
X1115962Y-119614D01*
X1115089Y-121363D01*
X1114434Y-123697D01*
X1114216Y-126322D01*
X1114434Y-128947D01*
X1115089Y-131281D01*
X1115962Y-133031D01*
X1117272Y-134489D01*
X1119019Y-135072D01*
X1120765Y-134489D01*
X1122076Y-133031D01*
X1122949Y-131281D01*
X1123604Y-128947D01*
X1123822Y-126322D01*
X1123604Y-123697D01*
X1122949Y-121363D01*
X1122076Y-119614D01*
X1120765Y-118155D01*
X1119019Y-117572D01*
G01X1136082Y-135072D02*
X1136519Y-131281D01*
X1137174Y-128072D01*
X1138047Y-125155D01*
X1139139Y-121947D01*
X1140886Y-117572D01*
X1132152D01*
G01X1150089Y-135655D02*
X1157949Y-117572D01*
G01X1167371Y-120489D02*
X1168681Y-118739D01*
X1170209Y-117864D01*
X1171956Y-117572D01*
X1174139Y-118155D01*
X1175667Y-119614D01*
X1176104Y-121363D01*
X1175886Y-123114D01*
X1175012Y-124572D01*
X1170646Y-127489D01*
X1168681Y-129530D01*
X1167371Y-132448D01*
X1166934Y-135072D01*
X1176104D01*
G01X1189019Y-117572D02*
X1187272Y-118155D01*
X1185962Y-119614D01*
X1185089Y-121363D01*
X1184434Y-123697D01*
X1184216Y-126322D01*
X1184434Y-128947D01*
X1185089Y-131281D01*
X1185962Y-133031D01*
X1187272Y-134489D01*
X1189019Y-135072D01*
X1190765Y-134489D01*
X1192076Y-133031D01*
X1192949Y-131281D01*
X1193604Y-128947D01*
X1193822Y-126322D01*
X1193604Y-123697D01*
X1192949Y-121363D01*
X1192076Y-119614D01*
X1190765Y-118155D01*
X1189019Y-117572D01*
G01X1206519Y-135072D02*
Y-117572D01*
X1203899Y-121072D01*
G01Y-135072D02*
X1209139D01*
G01X1223582D02*
X1224019Y-131281D01*
X1224674Y-128072D01*
X1225547Y-125155D01*
X1226639Y-121947D01*
X1228386Y-117572D01*
X1219652D01*
G01X1114216Y-90072D02*
Y-72572D01*
X1118582D01*
X1120329Y-73447D01*
X1121639Y-74614D01*
X1122731Y-76363D01*
X1123604Y-78406D01*
X1123822Y-81322D01*
X1123604Y-84239D01*
X1122731Y-86281D01*
X1121639Y-88031D01*
X1120329Y-89197D01*
X1118582Y-90072D01*
X1114216D01*
G01X1140449D02*
Y-78406D01*
G01Y-80447D02*
X1139576Y-79281D01*
X1138265Y-78697D01*
X1136737Y-78406D01*
X1135209Y-78989D01*
X1133899Y-80155D01*
X1133025Y-81905D01*
X1132589Y-84239D01*
X1133025Y-86572D01*
X1133899Y-88322D01*
X1135209Y-89489D01*
X1136737Y-90072D01*
X1138265Y-89780D01*
X1139576Y-88906D01*
X1140449Y-87739D01*
G01X1154019Y-72572D02*
Y-90072D01*
G01X1150962Y-78406D02*
X1157076D01*
G01X1168244Y-82197D02*
X1175231D01*
X1174576Y-80155D01*
X1173484Y-78989D01*
X1171956Y-78406D01*
X1170427Y-78697D01*
X1169117Y-79572D01*
X1168244Y-81614D01*
X1167807Y-83364D01*
Y-85114D01*
X1168244Y-86864D01*
X1169336Y-88614D01*
X1170646Y-89780D01*
X1172174Y-90072D01*
X1173702Y-89489D01*
X1175231Y-87739D01*
G54D19*
X65400Y546000D03*
X78231Y562399D03*
X92870Y564415D03*
X97113Y564386D03*
X100619Y564385D03*
X137100Y592000D03*
X133600D03*
X207500Y495580D03*
X252670Y620437D03*
X224346Y621995D03*
X245200Y688300D03*
X365400Y508000D03*
X367600Y701900D03*
X645000Y552900D03*
X721400Y278200D03*
X790360Y239400D03*
G54D73*
X652756Y180000D03*
X865353Y332598D03*
G54D28*
X90157Y413583D03*
X309055Y157677D03*
G54D46*
X165382Y475793D03*
Y473233D03*
Y470673D03*
Y468113D03*
X181562D03*
Y470673D03*
Y473233D03*
Y475793D03*
X326300Y675780D03*
Y673220D03*
Y670660D03*
Y668100D03*
Y665540D03*
Y662980D03*
Y660420D03*
X348500D03*
Y662980D03*
Y665540D03*
Y668100D03*
Y670660D03*
Y673220D03*
Y675780D03*
G54D37*
X96287Y576499D03*
X307900Y514300D03*
X356600Y524400D03*
X356480Y590440D03*
X378500Y578300D03*
X647500Y203400D03*
X648698Y299889D03*
X799200Y218150D03*
X795719Y218124D03*
X797099Y243345D03*
X796829Y234125D03*
X792269Y218094D03*
X764900Y213800D03*
X768479Y212264D03*
X759000Y214700D03*
X806210Y218140D03*
X802650Y218130D03*
G54D64*
X488838Y137225D03*
G54D55*
X316000Y671850D03*
X665500Y201900D03*
X657500Y281500D03*
X648000Y281300D03*
G54D29*
X113900Y497300D03*
X165935Y481762D03*
X152316Y570304D03*
X175579Y583387D03*
X179260Y611180D03*
Y607480D03*
X207350Y633450D03*
X266805Y549594D03*
X236400Y633900D03*
X359600Y541400D03*
X369089Y554000D03*
X560800Y64700D03*
X584600Y77400D03*
X665800Y421500D03*
Y417500D03*
Y413500D03*
Y426000D03*
X727268Y294464D03*
X790750Y234770D03*
X757100Y262350D03*
X790900Y224400D03*
X790750Y231350D03*
Y227900D03*
X749600Y262350D03*
X748250Y268900D03*
X734768Y294464D03*
X742268D03*
X756050Y268900D03*
G54D38*
X96287Y572899D03*
X307900Y510700D03*
X356600Y520800D03*
X356480Y586840D03*
X378500Y574700D03*
X647500Y199800D03*
X648698Y296289D03*
X799200Y214550D03*
X795719Y214524D03*
X797099Y239745D03*
X796829Y230525D03*
X792269Y214494D03*
X764900Y210200D03*
X768479Y208664D03*
X759000Y211100D03*
X806210Y214540D03*
X802650Y214530D03*
G54D65*
X488838Y164744D03*
G54D74*
X658585Y152347D03*
Y150147D03*
X656085Y152347D03*
Y150147D03*
X663784Y152447D03*
Y150247D03*
X661284Y152447D03*
Y150247D03*
X666685Y152447D03*
Y150247D03*
X653384Y152347D03*
Y150147D03*
X650884Y152347D03*
Y150147D03*
X669185Y152447D03*
Y150247D03*
X786880Y262090D03*
Y259890D03*
X781580Y261940D03*
Y259740D03*
X790800Y297700D03*
Y295500D03*
X770800Y302100D03*
Y299900D03*
X757000Y277950D03*
Y275750D03*
X752000Y288200D03*
Y286000D03*
X754800Y277950D03*
Y275750D03*
X775200Y280800D03*
Y278600D03*
X803100Y292800D03*
Y290600D03*
G54D56*
X346457Y66850D03*
Y57007D03*
X353543Y70787D03*
Y62913D03*
Y55039D03*
X346457Y74724D03*
Y84567D03*
X353543Y86535D03*
Y78661D03*
G54D47*
X193238Y465985D03*
X201801Y684252D03*
X225601D03*
G54D48*
X163189Y669291D03*
G54D39*
X137824Y544746D03*
Y552346D03*
X135449Y558949D03*
Y566549D03*
X122600Y589800D03*
Y597400D03*
X149700Y723000D03*
Y715400D03*
X220300Y525700D03*
Y518100D03*
X247070Y619140D03*
Y626740D03*
X239346Y626876D03*
Y619276D03*
X312272Y192744D03*
Y200344D03*
X327612Y231754D03*
Y239354D03*
X327552Y225184D03*
Y217584D03*
X477943Y34165D03*
Y41765D03*
X679500Y302700D03*
Y310300D03*
X712780Y316840D03*
Y324440D03*
X770090Y226880D03*
Y219280D03*
X760650Y236070D03*
Y228470D03*
X741650Y235600D03*
Y228000D03*
X770300Y270000D03*
Y277600D03*
X801226Y361756D03*
Y369356D03*
X809326Y369256D03*
Y361656D03*
G54D57*
X380500Y24500D03*
X369500D03*
X467500Y25500D03*
X478500D03*
X744100Y474900D03*
X755100D03*
G54D75*
X622025Y211250D03*
X623995D03*
X625960D03*
X627930D03*
X629900D03*
X631870D03*
X633835D03*
X635805D03*
X637775D03*
X639740D03*
X641710D03*
X643680D03*
X645645D03*
X647615D03*
X649585D03*
X651555D03*
X653520D03*
X655490D03*
X657460D03*
X659425D03*
X661395D03*
X663365D03*
X665330D03*
X667300D03*
Y286950D03*
X665330D03*
X663365D03*
X661395D03*
X659425D03*
X657460D03*
X655490D03*
X653520D03*
X651555D03*
X649585D03*
X647615D03*
X645645D03*
X643680D03*
X641710D03*
X639740D03*
X637775D03*
X635805D03*
X633835D03*
X631870D03*
X629900D03*
X627930D03*
X625960D03*
X623995D03*
X622025D03*
X669270Y211250D03*
X671240D03*
X673205D03*
X675175D03*
Y286950D03*
X673205D03*
X671240D03*
X669270D03*
G54D66*
X564803Y24409D03*
X574803D03*
X584803D03*
X753780D03*
X763780D03*
X773780D03*
X801024D03*
X811024D03*
X821024D03*
G54D58*
X373850Y563338D03*
X366350Y559463D03*
Y567213D03*
G54D49*
X214040Y504230D03*
X216600D03*
X219160D03*
Y497730D03*
X214040D03*
G54D76*
X689500Y305900D03*
Y308100D03*
X692000Y305900D03*
Y308100D03*
X774350Y255250D03*
Y257450D03*
X791617Y318400D03*
Y320600D03*
X793817Y318400D03*
Y320600D03*
X788817Y318400D03*
Y320600D03*
X740117Y318400D03*
Y320600D03*
X742317Y318400D03*
Y320600D03*
X746617Y318400D03*
Y320600D03*
X748817Y318400D03*
Y320600D03*
X754617Y318400D03*
Y320600D03*
X756817Y318400D03*
Y320600D03*
X759617Y318400D03*
Y320600D03*
X761817Y318400D03*
Y320600D03*
X776617Y318400D03*
Y320600D03*
X778817Y318400D03*
Y320600D03*
X781617Y318400D03*
Y320600D03*
X783817Y318400D03*
Y320600D03*
X786617Y318400D03*
Y320600D03*
X777700Y307300D03*
Y309500D03*
G54D67*
X601500Y367550D03*
X598941D03*
X601500Y359650D03*
X598941D03*
X604059Y367550D03*
Y359650D03*
G54D59*
X361800Y603500D03*
Y599900D03*
X367620Y603164D03*
Y599564D03*
G54D68*
X601500Y363600D03*
G54D77*
X699925Y313194D03*
Y324194D03*
X786600Y452500D03*
Y441500D03*
X777600Y452500D03*
Y441500D03*
G54D78*
X733469Y481247D03*
G54D69*
X601500Y363600D03*
G54D79*
X755785Y91500D03*
X753585D03*
X755785Y94000D03*
X753585D03*
X755784Y99500D03*
X753584D03*
X755784Y102000D03*
X753584D03*
X755785Y83500D03*
X753585D03*
X755785Y75500D03*
X753585D03*
X755785Y78000D03*
X753585D03*
X755785Y86000D03*
X753585D03*
X778900Y206500D03*
X776700D03*
X792802Y206042D03*
X790602D03*
X760500Y204300D03*
X758300D03*
X778900Y208700D03*
X776700D03*
X792802Y208542D03*
X790602D03*
X760608Y284964D03*
X758408D03*
X789600Y280500D03*
X787400D03*
X781740Y269030D03*
X779540D03*
X765979Y284964D03*
X763779D03*
X807316Y206045D03*
X805116D03*
X807256Y208363D03*
X805056D03*
X806068Y278464D03*
X803868D03*
X805868Y270664D03*
X803668D03*
M02*
